G04 ================== begin FILE IDENTIFICATION RECORD ==================*
G04 Layout Name:  D:/<user>/Wistron_project/16347-sc/gbr/16347-sc.brd*
G04 Film Name:    16347-sc_X_Y*
G04 File Format:  Gerber RS274X*
G04 File Origin:  Cadence Allegro 16.5-S056*
G04 Origin Date:  Tue Mar 14 17:08:14 2017*
G04 *
G04 Layer:  BOARD GEOMETRY/PANEL_DRAWING*
G04 *
G04 Offset:    (0.00 0.00)*
G04 Mirror:    No*
G04 Mode:      Positive*
G04 Rotation:  0*
G04 FullContactRelief:  No*
G04 UndefLineWidth:     6.00*
G04 ================== end FILE IDENTIFICATION RECORD ====================*
%FSLAX35Y35*MOIN*%
%IR0*IPPOS*OFA0.00000B0.00000*MIA0B0*SFA1.00000B1.00000*%
%ADD10C,.006*%
G75*
%LPD*%
G75*
G54D10*
G01X-489817Y-514041D02*
X-489078Y-515222D01*
X-488193Y-516009D01*
X-487159Y-516403D01*
X-485978Y-516009D01*
X-485092Y-515222D01*
X-484206Y-514041D01*
X-483911Y-512466D01*
Y-504592D01*
G01X-488636Y-288710D02*
X-485093D01*
G01X-486864D02*
Y-300521D01*
G01X-488636D02*
X-485093D01*
G01X-489964Y-84829D02*
Y-73018D01*
G01X-483764D02*
Y-84829D01*
G01Y-78924D02*
X-489964D01*
G01X-485978Y136958D02*
X-483025D01*
Y133415D01*
X-483911Y132234D01*
X-484945Y131447D01*
X-486421Y131053D01*
X-487897Y131447D01*
X-488931Y132234D01*
X-489817Y133415D01*
X-490407Y134793D01*
X-490703Y136368D01*
Y137746D01*
X-490407Y138927D01*
X-489817Y140305D01*
X-488931Y141486D01*
X-488045Y142273D01*
X-486864Y142864D01*
X-485831D01*
X-484650Y142470D01*
X-483764Y141683D01*
G01X-490047Y347125D02*
Y358936D01*
X-484437D01*
G01X-486504Y353227D02*
X-490047D01*
G01X-483911Y563196D02*
X-489817D01*
Y575007D01*
X-483911D01*
G01X-486273Y569298D02*
X-489817D01*
G01X-490112Y778888D02*
Y790699D01*
X-487159D01*
X-485978Y790108D01*
X-485092Y789321D01*
X-484354Y788140D01*
X-483764Y786762D01*
X-483616Y784793D01*
X-483764Y782825D01*
X-484354Y781447D01*
X-485092Y780266D01*
X-485978Y779478D01*
X-487159Y778888D01*
X-490112D01*
G01X-483616Y1005787D02*
X-484502Y1006377D01*
X-485535Y1006771D01*
X-486716D01*
X-488045Y1006180D01*
X-489078Y1005196D01*
X-489817Y1004015D01*
X-490407Y1002047D01*
X-490555Y1000275D01*
X-490260Y998503D01*
X-489817Y997322D01*
X-488931Y996141D01*
X-487897Y995354D01*
X-486864Y994960D01*
X-485831D01*
X-484797Y995354D01*
X-483911Y995944D01*
X-483173Y996731D01*
G01X-485683Y1216951D02*
X-485092Y1217542D01*
X-484650Y1218526D01*
X-484354Y1219904D01*
X-484650Y1221085D01*
X-485240Y1221872D01*
X-486273Y1222463D01*
X-490260D01*
Y1210652D01*
X-485388D01*
X-484354Y1211439D01*
X-483764Y1212620D01*
X-483468Y1213998D01*
X-483764Y1215376D01*
X-484650Y1216557D01*
X-485683Y1216951D01*
X-490260D01*
G01X-490555Y1426534D02*
X-486864Y1438345D01*
X-483173Y1426534D01*
G01X-484502Y1430668D02*
X-489226D01*
G01X-359986Y-633813D02*
Y-622002D01*
X-361758Y-624364D01*
G01Y-633813D02*
X-358215D01*
G01X-359986Y1543943D02*
Y1555754D01*
X-361758Y1553392D01*
G01Y1543943D02*
X-358215D01*
G01X-145015Y-623970D02*
X-144129Y-622790D01*
X-143096Y-622199D01*
X-141915Y-622002D01*
X-140438Y-622396D01*
X-139405Y-623380D01*
X-139110Y-624561D01*
X-139257Y-625742D01*
X-139848Y-626726D01*
X-142801Y-628695D01*
X-144129Y-630073D01*
X-145015Y-632042D01*
X-145310Y-633813D01*
X-139110D01*
G01X-99433Y116D02*
X-100221Y-146D01*
X-100811Y-803D01*
X-101205Y-1590D01*
X-101500Y-2640D01*
X-101599Y-3821D01*
X-101500Y-5002D01*
X-101205Y-6052D01*
X-100811Y-6840D01*
X-100221Y-7496D01*
X-99433Y-7758D01*
X-98646Y-7496D01*
X-98055Y-6840D01*
X-97661Y-6052D01*
X-97366Y-5002D01*
X-97267Y-3821D01*
X-97366Y-2640D01*
X-97661Y-1590D01*
X-98055Y-803D01*
X-98646Y-146D01*
X-99433Y116D01*
G01X-91558Y-8020D02*
X-91755Y-7889D01*
Y-7627D01*
X-91558Y-7496D01*
X-91361Y-7627D01*
Y-7889D01*
X-91558Y-8020D01*
G01X-83683Y116D02*
X-84471Y-146D01*
X-85061Y-803D01*
X-85455Y-1590D01*
X-85750Y-2640D01*
X-85849Y-3821D01*
X-85750Y-5002D01*
X-85455Y-6052D01*
X-85061Y-6840D01*
X-84471Y-7496D01*
X-83683Y-7758D01*
X-82896Y-7496D01*
X-82305Y-6840D01*
X-81911Y-6052D01*
X-81616Y-5002D01*
X-81517Y-3821D01*
X-81616Y-2640D01*
X-81911Y-1590D01*
X-82305Y-803D01*
X-82896Y-146D01*
X-83683Y116D01*
G01X-75808D02*
X-76596Y-146D01*
X-77186Y-803D01*
X-77580Y-1590D01*
X-77875Y-2640D01*
X-77974Y-3821D01*
X-77875Y-5002D01*
X-77580Y-6052D01*
X-77186Y-6840D01*
X-76596Y-7496D01*
X-75808Y-7758D01*
X-75021Y-7496D01*
X-74430Y-6840D01*
X-74036Y-6052D01*
X-73741Y-5002D01*
X-73642Y-3821D01*
X-73741Y-2640D01*
X-74036Y-1590D01*
X-74430Y-803D01*
X-75021Y-146D01*
X-75808Y116D01*
G01X-108661Y67856D02*
Y75730D01*
X-109842Y74155D01*
G01Y67856D02*
X-107480D01*
G01X-102459Y68774D02*
X-101770Y68118D01*
X-100983Y67856D01*
X-100195Y68118D01*
X-99506Y68906D01*
X-99014Y70087D01*
X-98817Y71268D01*
Y72712D01*
X-99014Y73893D01*
X-99506Y74943D01*
X-100097Y75468D01*
X-100786Y75730D01*
X-101574Y75468D01*
X-102164Y74943D01*
X-102558Y74155D01*
X-102755Y73105D01*
X-102558Y72187D01*
X-102066Y71268D01*
X-101475Y70743D01*
X-100786Y70612D01*
X-99999Y70874D01*
X-99408Y71530D01*
X-98817Y72712D01*
G01X-92911Y67594D02*
X-93108Y67725D01*
Y67987D01*
X-92911Y68118D01*
X-92714Y67987D01*
Y67725D01*
X-92911Y67594D01*
G01X-86906Y74418D02*
X-86316Y75205D01*
X-85627Y75599D01*
X-84839Y75730D01*
X-83855Y75468D01*
X-83166Y74811D01*
X-82969Y74024D01*
X-83067Y73236D01*
X-83461Y72580D01*
X-85430Y71268D01*
X-86316Y70349D01*
X-86906Y69037D01*
X-87103Y67856D01*
X-82969D01*
G01X-77161Y75730D02*
X-77949Y75468D01*
X-78539Y74811D01*
X-78933Y74024D01*
X-79228Y72974D01*
X-79327Y71793D01*
X-79228Y70612D01*
X-78933Y69562D01*
X-78539Y68774D01*
X-77949Y68118D01*
X-77161Y67856D01*
X-76374Y68118D01*
X-75783Y68774D01*
X-75389Y69562D01*
X-75094Y70612D01*
X-74995Y71793D01*
X-75094Y72974D01*
X-75389Y74024D01*
X-75783Y74811D01*
X-76374Y75468D01*
X-77161Y75730D01*
G01X-107349Y43446D02*
Y51320D01*
X-108530Y49745D01*
G01Y43446D02*
X-106168D01*
G01X-101640Y45021D02*
X-101049Y44102D01*
X-100262Y43577D01*
X-99375Y43446D01*
X-98588Y43577D01*
X-97801Y44233D01*
X-97308Y45021D01*
X-97210Y45808D01*
X-97407Y46727D01*
X-98096Y47383D01*
X-98785Y47646D01*
X-99671D01*
G01X-98785D02*
X-98194Y48039D01*
X-97702Y48695D01*
X-97505Y49483D01*
X-97702Y50270D01*
X-98194Y50926D01*
X-99080Y51320D01*
X-99966Y51189D01*
X-100852Y50664D01*
G01X-91599Y43184D02*
X-91796Y43315D01*
Y43577D01*
X-91599Y43708D01*
X-91402Y43577D01*
Y43315D01*
X-91599Y43184D01*
G01X-83724Y51320D02*
X-84512Y51058D01*
X-85102Y50401D01*
X-85496Y49614D01*
X-85791Y48564D01*
X-85890Y47383D01*
X-85791Y46202D01*
X-85496Y45152D01*
X-85102Y44364D01*
X-84512Y43708D01*
X-83724Y43446D01*
X-82937Y43708D01*
X-82346Y44364D01*
X-81952Y45152D01*
X-81657Y46202D01*
X-81558Y47383D01*
X-81657Y48564D01*
X-81952Y49614D01*
X-82346Y50401D01*
X-82937Y51058D01*
X-83724Y51320D01*
G01X-75849D02*
X-76637Y51058D01*
X-77227Y50401D01*
X-77621Y49614D01*
X-77916Y48564D01*
X-78015Y47383D01*
X-77916Y46202D01*
X-77621Y45152D01*
X-77227Y44364D01*
X-76637Y43708D01*
X-75849Y43446D01*
X-75062Y43708D01*
X-74471Y44364D01*
X-74077Y45152D01*
X-73782Y46202D01*
X-73683Y47383D01*
X-73782Y48564D01*
X-74077Y49614D01*
X-74471Y50401D01*
X-75062Y51058D01*
X-75849Y51320D01*
G01X-109415Y120752D02*
X-108824Y119833D01*
X-108037Y119308D01*
X-107150Y119177D01*
X-106363Y119308D01*
X-105576Y119964D01*
X-105083Y120752D01*
X-104985Y121539D01*
X-105182Y122458D01*
X-105871Y123114D01*
X-106560Y123377D01*
X-107446D01*
G01X-106560D02*
X-105969Y123770D01*
X-105477Y124426D01*
X-105280Y125214D01*
X-105477Y126001D01*
X-105969Y126657D01*
X-106855Y127051D01*
X-107741Y126920D01*
X-108627Y126395D01*
G01X-101244Y125739D02*
X-100654Y126526D01*
X-99965Y126920D01*
X-99177Y127051D01*
X-98193Y126789D01*
X-97504Y126132D01*
X-97307Y125345D01*
X-97405Y124557D01*
X-97799Y123901D01*
X-99768Y122589D01*
X-100654Y121670D01*
X-101244Y120358D01*
X-101441Y119177D01*
X-97307D01*
G01X-91499Y118915D02*
X-91696Y119046D01*
Y119308D01*
X-91499Y119439D01*
X-91302Y119308D01*
Y119046D01*
X-91499Y118915D01*
G01X-85494Y125739D02*
X-84904Y126526D01*
X-84215Y126920D01*
X-83427Y127051D01*
X-82443Y126789D01*
X-81754Y126132D01*
X-81557Y125345D01*
X-81655Y124557D01*
X-82049Y123901D01*
X-84018Y122589D01*
X-84904Y121670D01*
X-85494Y120358D01*
X-85691Y119177D01*
X-81557D01*
G01X-75749Y127051D02*
X-76537Y126789D01*
X-77127Y126132D01*
X-77521Y125345D01*
X-77816Y124295D01*
X-77915Y123114D01*
X-77816Y121933D01*
X-77521Y120883D01*
X-77127Y120095D01*
X-76537Y119439D01*
X-75749Y119177D01*
X-74962Y119439D01*
X-74371Y120095D01*
X-73977Y120883D01*
X-73682Y121933D01*
X-73583Y123114D01*
X-73682Y124295D01*
X-73977Y125345D01*
X-74371Y126132D01*
X-74962Y126789D01*
X-75749Y127051D01*
G01X-109462Y132484D02*
X-108871Y131565D01*
X-108084Y131040D01*
X-107197Y130909D01*
X-106410Y131040D01*
X-105623Y131696D01*
X-105130Y132484D01*
X-105032Y133271D01*
X-105229Y134190D01*
X-105918Y134846D01*
X-106607Y135109D01*
X-107493D01*
G01X-106607D02*
X-106016Y135502D01*
X-105524Y136158D01*
X-105327Y136946D01*
X-105524Y137733D01*
X-106016Y138389D01*
X-106902Y138783D01*
X-107788Y138652D01*
X-108674Y138127D01*
G01X-98240Y130909D02*
Y138783D01*
X-101882Y133140D01*
X-96960D01*
G01X-91546Y130647D02*
X-91743Y130778D01*
Y131040D01*
X-91546Y131171D01*
X-91349Y131040D01*
Y130778D01*
X-91546Y130647D01*
G01X-85541Y137471D02*
X-84951Y138258D01*
X-84262Y138652D01*
X-83474Y138783D01*
X-82490Y138521D01*
X-81801Y137864D01*
X-81604Y137077D01*
X-81702Y136289D01*
X-82096Y135633D01*
X-84065Y134321D01*
X-84951Y133402D01*
X-85541Y132090D01*
X-85738Y130909D01*
X-81604D01*
G01X-75796Y138783D02*
X-76584Y138521D01*
X-77174Y137864D01*
X-77568Y137077D01*
X-77863Y136027D01*
X-77962Y134846D01*
X-77863Y133665D01*
X-77568Y132615D01*
X-77174Y131827D01*
X-76584Y131171D01*
X-75796Y130909D01*
X-75009Y131171D01*
X-74418Y131827D01*
X-74024Y132615D01*
X-73729Y133665D01*
X-73630Y134846D01*
X-73729Y136027D01*
X-74024Y137077D01*
X-74418Y137864D01*
X-75009Y138521D01*
X-75796Y138783D01*
G01X-109693Y203823D02*
X-109102Y203167D01*
X-108413Y202773D01*
X-107527Y202642D01*
X-106641Y202904D01*
X-105952Y203429D01*
X-105460Y204348D01*
X-105361Y205398D01*
X-105558Y206448D01*
X-106051Y207104D01*
X-106740Y207629D01*
X-107428Y207760D01*
X-108118Y207629D01*
X-109003Y207104D01*
X-108708Y210516D01*
X-106051D01*
G01X-101818Y204217D02*
X-101227Y203298D01*
X-100440Y202773D01*
X-99553Y202642D01*
X-98766Y202773D01*
X-97979Y203429D01*
X-97486Y204217D01*
X-97388Y205004D01*
X-97585Y205923D01*
X-98274Y206579D01*
X-98963Y206842D01*
X-99849D01*
G01X-98963D02*
X-98372Y207235D01*
X-97880Y207891D01*
X-97683Y208679D01*
X-97880Y209466D01*
X-98372Y210122D01*
X-99258Y210516D01*
X-100144Y210385D01*
X-101030Y209860D01*
G01X-91777Y202380D02*
X-91974Y202511D01*
Y202773D01*
X-91777Y202904D01*
X-91580Y202773D01*
Y202511D01*
X-91777Y202380D01*
G01X-82721Y202642D02*
Y210516D01*
X-86363Y204873D01*
X-81441D01*
G01X-76027Y210516D02*
X-76815Y210254D01*
X-77405Y209597D01*
X-77799Y208810D01*
X-78094Y207760D01*
X-78193Y206579D01*
X-78094Y205398D01*
X-77799Y204348D01*
X-77405Y203560D01*
X-76815Y202904D01*
X-76027Y202642D01*
X-75240Y202904D01*
X-74649Y203560D01*
X-74255Y204348D01*
X-73960Y205398D01*
X-73861Y206579D01*
X-73960Y207760D01*
X-74255Y208810D01*
X-74649Y209597D01*
X-75240Y210254D01*
X-76027Y210516D01*
G01X-106346Y178232D02*
Y186106D01*
X-109988Y180463D01*
X-105066D01*
G01X-99849Y178232D02*
X-99652Y179938D01*
X-99357Y181381D01*
X-98963Y182694D01*
X-98471Y184137D01*
X-97683Y186106D01*
X-101621D01*
G01X-91777Y177970D02*
X-91974Y178101D01*
Y178363D01*
X-91777Y178494D01*
X-91580Y178363D01*
Y178101D01*
X-91777Y177970D01*
G01X-85772Y184794D02*
X-85182Y185581D01*
X-84493Y185975D01*
X-83705Y186106D01*
X-82721Y185844D01*
X-82032Y185187D01*
X-81835Y184400D01*
X-81933Y183612D01*
X-82327Y182956D01*
X-84296Y181644D01*
X-85182Y180725D01*
X-85772Y179413D01*
X-85969Y178232D01*
X-81835D01*
G01X-76027Y186106D02*
X-76815Y185844D01*
X-77405Y185187D01*
X-77799Y184400D01*
X-78094Y183350D01*
X-78193Y182169D01*
X-78094Y180988D01*
X-77799Y179938D01*
X-77405Y179150D01*
X-76815Y178494D01*
X-76027Y178232D01*
X-75240Y178494D01*
X-74649Y179150D01*
X-74255Y179938D01*
X-73960Y180988D01*
X-73861Y182169D01*
X-73960Y183350D01*
X-74255Y184400D01*
X-74649Y185187D01*
X-75240Y185844D01*
X-76027Y186106D01*
G01X-108617Y268122D02*
X-107928Y269041D01*
X-107338Y269565D01*
X-106550Y269828D01*
X-105861Y269565D01*
X-105369Y269041D01*
X-104975Y268253D01*
X-104877Y267334D01*
X-104975Y266547D01*
X-105369Y265759D01*
X-105960Y265103D01*
X-106648Y264841D01*
X-107436Y265103D01*
X-108125Y265891D01*
X-108519Y267072D01*
X-108617Y268384D01*
X-108420Y270090D01*
X-108125Y271009D01*
X-107633Y271928D01*
X-106944Y272584D01*
X-106255Y272715D01*
X-105566Y272453D01*
X-105074Y271796D01*
G01X-98872Y264841D02*
X-98183Y264972D01*
X-97396Y265366D01*
X-96903Y266022D01*
X-96706Y266941D01*
X-96903Y267859D01*
X-97494Y268647D01*
X-98380Y269041D01*
X-99364D01*
X-99955Y269303D01*
X-100447Y269959D01*
X-100644Y270878D01*
X-100348Y271796D01*
X-99660Y272453D01*
X-98872Y272715D01*
X-98085Y272453D01*
X-97396Y271796D01*
X-97100Y270878D01*
X-97297Y269959D01*
X-97789Y269303D01*
X-98380Y269041D01*
X-99364D01*
X-100250Y268647D01*
X-100841Y267859D01*
X-101038Y266941D01*
X-100841Y266022D01*
X-100348Y265366D01*
X-99561Y264972D01*
X-98872Y264841D01*
G01X-90997Y264579D02*
X-91194Y264710D01*
Y264972D01*
X-90997Y265103D01*
X-90800Y264972D01*
Y264710D01*
X-90997Y264579D01*
G01X-81941Y264841D02*
Y272715D01*
X-85583Y267072D01*
X-80661D01*
G01X-75247Y272715D02*
X-76035Y272453D01*
X-76625Y271796D01*
X-77019Y271009D01*
X-77314Y269959D01*
X-77413Y268778D01*
X-77314Y267597D01*
X-77019Y266547D01*
X-76625Y265759D01*
X-76035Y265103D01*
X-75247Y264841D01*
X-74460Y265103D01*
X-73869Y265759D01*
X-73475Y266547D01*
X-73180Y267597D01*
X-73081Y268778D01*
X-73180Y269959D01*
X-73475Y271009D01*
X-73869Y271796D01*
X-74460Y272453D01*
X-75247Y272715D01*
G01X-109397Y257103D02*
X-108708Y258022D01*
X-108118Y258546D01*
X-107330Y258809D01*
X-106641Y258546D01*
X-106149Y258022D01*
X-105755Y257234D01*
X-105657Y256315D01*
X-105755Y255528D01*
X-106149Y254740D01*
X-106740Y254084D01*
X-107428Y253822D01*
X-108216Y254084D01*
X-108905Y254872D01*
X-109299Y256053D01*
X-109397Y257365D01*
X-109200Y259071D01*
X-108905Y259990D01*
X-108413Y260909D01*
X-107724Y261565D01*
X-107035Y261696D01*
X-106346Y261434D01*
X-105854Y260777D01*
G01X-101522Y257103D02*
X-100833Y258022D01*
X-100243Y258546D01*
X-99455Y258809D01*
X-98766Y258546D01*
X-98274Y258022D01*
X-97880Y257234D01*
X-97782Y256315D01*
X-97880Y255528D01*
X-98274Y254740D01*
X-98865Y254084D01*
X-99553Y253822D01*
X-100341Y254084D01*
X-101030Y254872D01*
X-101424Y256053D01*
X-101522Y257365D01*
X-101325Y259071D01*
X-101030Y259990D01*
X-100538Y260909D01*
X-99849Y261565D01*
X-99160Y261696D01*
X-98471Y261434D01*
X-97979Y260777D01*
G01X-91777Y253560D02*
X-91974Y253691D01*
Y253953D01*
X-91777Y254084D01*
X-91580Y253953D01*
Y253691D01*
X-91777Y253560D01*
G01X-82721Y253822D02*
Y261696D01*
X-86363Y256053D01*
X-81441D01*
G01X-76027Y261696D02*
X-76815Y261434D01*
X-77405Y260777D01*
X-77799Y259990D01*
X-78094Y258940D01*
X-78193Y257759D01*
X-78094Y256578D01*
X-77799Y255528D01*
X-77405Y254740D01*
X-76815Y254084D01*
X-76027Y253822D01*
X-75240Y254084D01*
X-74649Y254740D01*
X-74255Y255528D01*
X-73960Y256578D01*
X-73861Y257759D01*
X-73960Y258940D01*
X-74255Y259990D01*
X-74649Y260777D01*
X-75240Y261434D01*
X-76027Y261696D01*
G01X-107965Y311903D02*
X-107276Y312034D01*
X-106489Y312428D01*
X-105996Y313084D01*
X-105799Y314003D01*
X-105996Y314921D01*
X-106587Y315709D01*
X-107473Y316103D01*
X-108457D01*
X-109048Y316365D01*
X-109540Y317021D01*
X-109737Y317940D01*
X-109441Y318858D01*
X-108753Y319515D01*
X-107965Y319777D01*
X-107178Y319515D01*
X-106489Y318858D01*
X-106193Y317940D01*
X-106390Y317021D01*
X-106882Y316365D01*
X-107473Y316103D01*
X-108457D01*
X-109343Y315709D01*
X-109934Y314921D01*
X-110131Y314003D01*
X-109934Y313084D01*
X-109441Y312428D01*
X-108654Y312034D01*
X-107965Y311903D01*
G01X-100090D02*
Y319777D01*
X-101271Y318202D01*
G01Y311903D02*
X-98909D01*
G01X-92215Y311641D02*
X-92412Y311772D01*
Y312034D01*
X-92215Y312165D01*
X-92018Y312034D01*
Y311772D01*
X-92215Y311641D01*
G01X-83159Y311903D02*
Y319777D01*
X-86801Y314134D01*
X-81879D01*
G01X-76465Y319777D02*
X-77253Y319515D01*
X-77843Y318858D01*
X-78237Y318071D01*
X-78532Y317021D01*
X-78631Y315840D01*
X-78532Y314659D01*
X-78237Y313609D01*
X-77843Y312821D01*
X-77253Y312165D01*
X-76465Y311903D01*
X-75678Y312165D01*
X-75087Y312821D01*
X-74693Y313609D01*
X-74398Y314659D01*
X-74299Y315840D01*
X-74398Y317021D01*
X-74693Y318071D01*
X-75087Y318858D01*
X-75678Y319515D01*
X-76465Y319777D01*
G01X-110590Y336313D02*
X-109901Y336444D01*
X-109114Y336838D01*
X-108621Y337494D01*
X-108424Y338413D01*
X-108621Y339331D01*
X-109212Y340119D01*
X-110098Y340513D01*
X-111082D01*
X-111673Y340775D01*
X-112165Y341431D01*
X-112362Y342350D01*
X-112066Y343268D01*
X-111378Y343925D01*
X-110590Y344187D01*
X-109803Y343925D01*
X-109114Y343268D01*
X-108818Y342350D01*
X-109015Y341431D01*
X-109507Y340775D01*
X-110098Y340513D01*
X-111082D01*
X-111968Y340119D01*
X-112559Y339331D01*
X-112756Y338413D01*
X-112559Y337494D01*
X-112066Y336838D01*
X-111279Y336444D01*
X-110590Y336313D01*
G01X-102912D02*
X-102715Y338019D01*
X-102420Y339462D01*
X-102026Y340775D01*
X-101534Y342218D01*
X-100746Y344187D01*
X-104684D01*
G01X-94840Y336051D02*
X-95037Y336182D01*
Y336444D01*
X-94840Y336575D01*
X-94643Y336444D01*
Y336182D01*
X-94840Y336051D01*
G01X-88835Y339594D02*
X-88146Y340513D01*
X-87556Y341037D01*
X-86768Y341300D01*
X-86079Y341037D01*
X-85587Y340513D01*
X-85193Y339725D01*
X-85095Y338806D01*
X-85193Y338019D01*
X-85587Y337231D01*
X-86178Y336575D01*
X-86866Y336313D01*
X-87654Y336575D01*
X-88343Y337363D01*
X-88737Y338544D01*
X-88835Y339856D01*
X-88638Y341562D01*
X-88343Y342481D01*
X-87851Y343400D01*
X-87162Y344056D01*
X-86473Y344187D01*
X-85784Y343925D01*
X-85292Y343268D01*
G01X-79090Y344187D02*
X-79878Y343925D01*
X-80468Y343268D01*
X-80862Y342481D01*
X-81157Y341431D01*
X-81256Y340250D01*
X-81157Y339069D01*
X-80862Y338019D01*
X-80468Y337231D01*
X-79878Y336575D01*
X-79090Y336313D01*
X-78303Y336575D01*
X-77712Y337231D01*
X-77318Y338019D01*
X-77023Y339069D01*
X-76924Y340250D01*
X-77023Y341431D01*
X-77318Y342481D01*
X-77712Y343268D01*
X-78303Y343925D01*
X-79090Y344187D01*
G01X-115701Y400670D02*
Y408544D01*
X-116882Y406969D01*
G01Y400670D02*
X-114520D01*
G01X-107826Y408544D02*
X-108614Y408282D01*
X-109204Y407625D01*
X-109598Y406838D01*
X-109893Y405788D01*
X-109992Y404607D01*
X-109893Y403426D01*
X-109598Y402376D01*
X-109204Y401588D01*
X-108614Y400932D01*
X-107826Y400670D01*
X-107039Y400932D01*
X-106448Y401588D01*
X-106054Y402376D01*
X-105759Y403426D01*
X-105660Y404607D01*
X-105759Y405788D01*
X-106054Y406838D01*
X-106448Y407625D01*
X-107039Y408282D01*
X-107826Y408544D01*
G01X-101821Y407232D02*
X-101231Y408019D01*
X-100542Y408413D01*
X-99754Y408544D01*
X-98770Y408282D01*
X-98081Y407625D01*
X-97884Y406838D01*
X-97982Y406050D01*
X-98376Y405394D01*
X-100345Y404082D01*
X-101231Y403163D01*
X-101821Y401851D01*
X-102018Y400670D01*
X-97884D01*
G01X-92076Y400408D02*
X-92273Y400539D01*
Y400801D01*
X-92076Y400932D01*
X-91879Y400801D01*
Y400539D01*
X-92076Y400408D01*
G01X-86071Y403951D02*
X-85382Y404870D01*
X-84792Y405394D01*
X-84004Y405657D01*
X-83315Y405394D01*
X-82823Y404870D01*
X-82429Y404082D01*
X-82331Y403163D01*
X-82429Y402376D01*
X-82823Y401588D01*
X-83414Y400932D01*
X-84102Y400670D01*
X-84890Y400932D01*
X-85579Y401720D01*
X-85973Y402901D01*
X-86071Y404213D01*
X-85874Y405919D01*
X-85579Y406838D01*
X-85087Y407757D01*
X-84398Y408413D01*
X-83709Y408544D01*
X-83020Y408282D01*
X-82528Y407625D01*
G01X-76326Y408544D02*
X-77114Y408282D01*
X-77704Y407625D01*
X-78098Y406838D01*
X-78393Y405788D01*
X-78492Y404607D01*
X-78393Y403426D01*
X-78098Y402376D01*
X-77704Y401588D01*
X-77114Y400932D01*
X-76326Y400670D01*
X-75539Y400932D01*
X-74948Y401588D01*
X-74554Y402376D01*
X-74259Y403426D01*
X-74160Y404607D01*
X-74259Y405788D01*
X-74554Y406838D01*
X-74948Y407625D01*
X-75539Y408282D01*
X-76326Y408544D01*
G01X-115581Y387773D02*
Y395647D01*
X-116762Y394072D01*
G01Y387773D02*
X-114400D01*
G01X-107706Y395647D02*
X-108494Y395385D01*
X-109084Y394728D01*
X-109478Y393941D01*
X-109773Y392891D01*
X-109872Y391710D01*
X-109773Y390529D01*
X-109478Y389479D01*
X-109084Y388691D01*
X-108494Y388035D01*
X-107706Y387773D01*
X-106919Y388035D01*
X-106328Y388691D01*
X-105934Y389479D01*
X-105639Y390529D01*
X-105540Y391710D01*
X-105639Y392891D01*
X-105934Y393941D01*
X-106328Y394728D01*
X-106919Y395385D01*
X-107706Y395647D01*
G01X-99831D02*
X-100619Y395385D01*
X-101209Y394728D01*
X-101603Y393941D01*
X-101898Y392891D01*
X-101997Y391710D01*
X-101898Y390529D01*
X-101603Y389479D01*
X-101209Y388691D01*
X-100619Y388035D01*
X-99831Y387773D01*
X-99044Y388035D01*
X-98453Y388691D01*
X-98059Y389479D01*
X-97764Y390529D01*
X-97665Y391710D01*
X-97764Y392891D01*
X-98059Y393941D01*
X-98453Y394728D01*
X-99044Y395385D01*
X-99831Y395647D01*
G01X-91956Y387511D02*
X-92153Y387642D01*
Y387904D01*
X-91956Y388035D01*
X-91759Y387904D01*
Y387642D01*
X-91956Y387511D01*
G01X-85951Y391054D02*
X-85262Y391973D01*
X-84672Y392497D01*
X-83884Y392760D01*
X-83195Y392497D01*
X-82703Y391973D01*
X-82309Y391185D01*
X-82211Y390266D01*
X-82309Y389479D01*
X-82703Y388691D01*
X-83294Y388035D01*
X-83982Y387773D01*
X-84770Y388035D01*
X-85459Y388823D01*
X-85853Y390004D01*
X-85951Y391316D01*
X-85754Y393022D01*
X-85459Y393941D01*
X-84967Y394860D01*
X-84278Y395516D01*
X-83589Y395647D01*
X-82900Y395385D01*
X-82408Y394728D01*
G01X-76206Y395647D02*
X-76994Y395385D01*
X-77584Y394728D01*
X-77978Y393941D01*
X-78273Y392891D01*
X-78372Y391710D01*
X-78273Y390529D01*
X-77978Y389479D01*
X-77584Y388691D01*
X-76994Y388035D01*
X-76206Y387773D01*
X-75419Y388035D01*
X-74828Y388691D01*
X-74434Y389479D01*
X-74139Y390529D01*
X-74040Y391710D01*
X-74139Y392891D01*
X-74434Y393941D01*
X-74828Y394728D01*
X-75419Y395385D01*
X-76206Y395647D01*
G01X-116417Y447384D02*
Y455258D01*
X-117598Y453683D01*
G01Y447384D02*
X-115236D01*
G01X-108542D02*
Y455258D01*
X-109723Y453683D01*
G01Y447384D02*
X-107361D01*
G01X-102833Y448565D02*
X-102242Y447909D01*
X-101553Y447515D01*
X-100667Y447384D01*
X-99781Y447646D01*
X-99092Y448171D01*
X-98600Y449090D01*
X-98501Y450140D01*
X-98698Y451190D01*
X-99191Y451846D01*
X-99880Y452371D01*
X-100568Y452502D01*
X-101258Y452371D01*
X-102143Y451846D01*
X-101848Y455258D01*
X-99191D01*
G01X-92792Y447122D02*
X-92989Y447253D01*
Y447515D01*
X-92792Y447646D01*
X-92595Y447515D01*
Y447253D01*
X-92792Y447122D01*
G01X-86787Y450665D02*
X-86098Y451584D01*
X-85508Y452108D01*
X-84720Y452371D01*
X-84031Y452108D01*
X-83539Y451584D01*
X-83145Y450796D01*
X-83047Y449877D01*
X-83145Y449090D01*
X-83539Y448302D01*
X-84130Y447646D01*
X-84818Y447384D01*
X-85606Y447646D01*
X-86295Y448434D01*
X-86689Y449615D01*
X-86787Y450927D01*
X-86590Y452633D01*
X-86295Y453552D01*
X-85803Y454471D01*
X-85114Y455127D01*
X-84425Y455258D01*
X-83736Y454996D01*
X-83244Y454339D01*
G01X-77042Y455258D02*
X-77830Y454996D01*
X-78420Y454339D01*
X-78814Y453552D01*
X-79109Y452502D01*
X-79208Y451321D01*
X-79109Y450140D01*
X-78814Y449090D01*
X-78420Y448302D01*
X-77830Y447646D01*
X-77042Y447384D01*
X-76255Y447646D01*
X-75664Y448302D01*
X-75270Y449090D01*
X-74975Y450140D01*
X-74876Y451321D01*
X-74975Y452502D01*
X-75270Y453552D01*
X-75664Y454339D01*
X-76255Y454996D01*
X-77042Y455258D01*
G01X-116417Y471794D02*
Y479668D01*
X-117598Y478093D01*
G01Y471794D02*
X-115236D01*
G01X-110412Y478356D02*
X-109822Y479143D01*
X-109133Y479537D01*
X-108345Y479668D01*
X-107361Y479406D01*
X-106672Y478749D01*
X-106475Y477962D01*
X-106573Y477174D01*
X-106967Y476518D01*
X-108936Y475206D01*
X-109822Y474287D01*
X-110412Y472975D01*
X-110609Y471794D01*
X-106475D01*
G01X-100667D02*
Y479668D01*
X-101848Y478093D01*
G01Y471794D02*
X-99486D01*
G01X-92792Y471532D02*
X-92989Y471663D01*
Y471925D01*
X-92792Y472056D01*
X-92595Y471925D01*
Y471663D01*
X-92792Y471532D01*
G01X-84917Y471794D02*
X-84228Y471925D01*
X-83441Y472319D01*
X-82948Y472975D01*
X-82751Y473894D01*
X-82948Y474812D01*
X-83539Y475600D01*
X-84425Y475994D01*
X-85409D01*
X-86000Y476256D01*
X-86492Y476912D01*
X-86689Y477831D01*
X-86393Y478749D01*
X-85705Y479406D01*
X-84917Y479668D01*
X-84130Y479406D01*
X-83441Y478749D01*
X-83145Y477831D01*
X-83342Y476912D01*
X-83834Y476256D01*
X-84425Y475994D01*
X-85409D01*
X-86295Y475600D01*
X-86886Y474812D01*
X-87083Y473894D01*
X-86886Y472975D01*
X-86393Y472319D01*
X-85606Y471925D01*
X-84917Y471794D01*
G01X-77042Y479668D02*
X-77830Y479406D01*
X-78420Y478749D01*
X-78814Y477962D01*
X-79109Y476912D01*
X-79208Y475731D01*
X-79109Y474550D01*
X-78814Y473500D01*
X-78420Y472712D01*
X-77830Y472056D01*
X-77042Y471794D01*
X-76255Y472056D01*
X-75664Y472712D01*
X-75270Y473500D01*
X-74975Y474550D01*
X-74876Y475731D01*
X-74975Y476912D01*
X-75270Y477962D01*
X-75664Y478749D01*
X-76255Y479406D01*
X-77042Y479668D01*
G01X-115001Y534893D02*
Y542767D01*
X-116182Y541192D01*
G01Y534893D02*
X-113820D01*
G01X-109292Y536468D02*
X-108701Y535549D01*
X-107914Y535024D01*
X-107027Y534893D01*
X-106240Y535024D01*
X-105453Y535680D01*
X-104960Y536468D01*
X-104862Y537255D01*
X-105059Y538174D01*
X-105748Y538830D01*
X-106437Y539093D01*
X-107323D01*
G01X-106437D02*
X-105846Y539486D01*
X-105354Y540142D01*
X-105157Y540930D01*
X-105354Y541717D01*
X-105846Y542373D01*
X-106732Y542767D01*
X-107618Y542636D01*
X-108504Y542111D01*
G01X-101121Y538174D02*
X-100432Y539093D01*
X-99842Y539617D01*
X-99054Y539880D01*
X-98365Y539617D01*
X-97873Y539093D01*
X-97479Y538305D01*
X-97381Y537386D01*
X-97479Y536599D01*
X-97873Y535811D01*
X-98464Y535155D01*
X-99152Y534893D01*
X-99940Y535155D01*
X-100629Y535943D01*
X-101023Y537124D01*
X-101121Y538436D01*
X-100924Y540142D01*
X-100629Y541061D01*
X-100137Y541980D01*
X-99448Y542636D01*
X-98759Y542767D01*
X-98070Y542505D01*
X-97578Y541848D01*
G01X-91376Y534631D02*
X-91573Y534762D01*
Y535024D01*
X-91376Y535155D01*
X-91179Y535024D01*
Y534762D01*
X-91376Y534631D01*
G01X-83501Y534893D02*
X-82812Y535024D01*
X-82025Y535418D01*
X-81532Y536074D01*
X-81335Y536993D01*
X-81532Y537911D01*
X-82123Y538699D01*
X-83009Y539093D01*
X-83993D01*
X-84584Y539355D01*
X-85076Y540011D01*
X-85273Y540930D01*
X-84977Y541848D01*
X-84289Y542505D01*
X-83501Y542767D01*
X-82714Y542505D01*
X-82025Y541848D01*
X-81729Y540930D01*
X-81926Y540011D01*
X-82418Y539355D01*
X-83009Y539093D01*
X-83993D01*
X-84879Y538699D01*
X-85470Y537911D01*
X-85667Y536993D01*
X-85470Y536074D01*
X-84977Y535418D01*
X-84190Y535024D01*
X-83501Y534893D01*
G01X-75626Y542767D02*
X-76414Y542505D01*
X-77004Y541848D01*
X-77398Y541061D01*
X-77693Y540011D01*
X-77792Y538830D01*
X-77693Y537649D01*
X-77398Y536599D01*
X-77004Y535811D01*
X-76414Y535155D01*
X-75626Y534893D01*
X-74839Y535155D01*
X-74248Y535811D01*
X-73854Y536599D01*
X-73559Y537649D01*
X-73460Y538830D01*
X-73559Y540011D01*
X-73854Y541061D01*
X-74248Y541848D01*
X-74839Y542505D01*
X-75626Y542767D01*
G01X-115839Y524089D02*
Y531963D01*
X-117020Y530388D01*
G01Y524089D02*
X-114658D01*
G01X-110130Y525664D02*
X-109539Y524745D01*
X-108752Y524220D01*
X-107865Y524089D01*
X-107078Y524220D01*
X-106291Y524876D01*
X-105798Y525664D01*
X-105700Y526451D01*
X-105897Y527370D01*
X-106586Y528026D01*
X-107275Y528289D01*
X-108161D01*
G01X-107275D02*
X-106684Y528682D01*
X-106192Y529338D01*
X-105995Y530126D01*
X-106192Y530913D01*
X-106684Y531569D01*
X-107570Y531963D01*
X-108456Y531832D01*
X-109342Y531307D01*
G01X-98908Y524089D02*
Y531963D01*
X-102550Y526320D01*
X-97628D01*
G01X-92214Y523827D02*
X-92411Y523958D01*
Y524220D01*
X-92214Y524351D01*
X-92017Y524220D01*
Y523958D01*
X-92214Y523827D01*
G01X-84339Y524089D02*
X-83650Y524220D01*
X-82863Y524614D01*
X-82370Y525270D01*
X-82173Y526189D01*
X-82370Y527107D01*
X-82961Y527895D01*
X-83847Y528289D01*
X-84831D01*
X-85422Y528551D01*
X-85914Y529207D01*
X-86111Y530126D01*
X-85815Y531044D01*
X-85127Y531701D01*
X-84339Y531963D01*
X-83552Y531701D01*
X-82863Y531044D01*
X-82567Y530126D01*
X-82764Y529207D01*
X-83256Y528551D01*
X-83847Y528289D01*
X-84831D01*
X-85717Y527895D01*
X-86308Y527107D01*
X-86505Y526189D01*
X-86308Y525270D01*
X-85815Y524614D01*
X-85028Y524220D01*
X-84339Y524089D01*
G01X-76464Y531963D02*
X-77252Y531701D01*
X-77842Y531044D01*
X-78236Y530257D01*
X-78531Y529207D01*
X-78630Y528026D01*
X-78531Y526845D01*
X-78236Y525795D01*
X-77842Y525007D01*
X-77252Y524351D01*
X-76464Y524089D01*
X-75677Y524351D01*
X-75086Y525007D01*
X-74692Y525795D01*
X-74397Y526845D01*
X-74298Y528026D01*
X-74397Y529207D01*
X-74692Y530257D01*
X-75086Y531044D01*
X-75677Y531701D01*
X-76464Y531963D01*
G01X-116535Y582866D02*
Y590740D01*
X-117716Y589165D01*
G01Y582866D02*
X-115354D01*
G01X-107479D02*
Y590740D01*
X-111121Y585097D01*
X-106199D01*
G01X-102458Y583784D02*
X-101769Y583128D01*
X-100982Y582866D01*
X-100194Y583128D01*
X-99505Y583916D01*
X-99013Y585097D01*
X-98816Y586278D01*
Y587722D01*
X-99013Y588903D01*
X-99505Y589953D01*
X-100096Y590478D01*
X-100785Y590740D01*
X-101573Y590478D01*
X-102163Y589953D01*
X-102557Y589165D01*
X-102754Y588115D01*
X-102557Y587197D01*
X-102065Y586278D01*
X-101474Y585753D01*
X-100785Y585622D01*
X-99998Y585884D01*
X-99407Y586540D01*
X-98816Y587722D01*
G01X-92910Y582604D02*
X-93107Y582735D01*
Y582997D01*
X-92910Y583128D01*
X-92713Y582997D01*
Y582735D01*
X-92910Y582604D01*
G01X-85035Y582866D02*
X-84346Y582997D01*
X-83559Y583391D01*
X-83066Y584047D01*
X-82869Y584966D01*
X-83066Y585884D01*
X-83657Y586672D01*
X-84543Y587066D01*
X-85527D01*
X-86118Y587328D01*
X-86610Y587984D01*
X-86807Y588903D01*
X-86511Y589821D01*
X-85823Y590478D01*
X-85035Y590740D01*
X-84248Y590478D01*
X-83559Y589821D01*
X-83263Y588903D01*
X-83460Y587984D01*
X-83952Y587328D01*
X-84543Y587066D01*
X-85527D01*
X-86413Y586672D01*
X-87004Y585884D01*
X-87201Y584966D01*
X-87004Y584047D01*
X-86511Y583391D01*
X-85724Y582997D01*
X-85035Y582866D01*
G01X-77160Y590740D02*
X-77948Y590478D01*
X-78538Y589821D01*
X-78932Y589034D01*
X-79227Y587984D01*
X-79326Y586803D01*
X-79227Y585622D01*
X-78932Y584572D01*
X-78538Y583784D01*
X-77948Y583128D01*
X-77160Y582866D01*
X-76373Y583128D01*
X-75782Y583784D01*
X-75388Y584572D01*
X-75093Y585622D01*
X-74994Y586803D01*
X-75093Y587984D01*
X-75388Y589034D01*
X-75782Y589821D01*
X-76373Y590478D01*
X-77160Y590740D01*
G01X-115223Y607276D02*
Y615150D01*
X-116404Y613575D01*
G01Y607276D02*
X-114042D01*
G01X-109514Y608457D02*
X-108923Y607801D01*
X-108234Y607407D01*
X-107348Y607276D01*
X-106462Y607538D01*
X-105773Y608063D01*
X-105281Y608982D01*
X-105182Y610032D01*
X-105379Y611082D01*
X-105872Y611738D01*
X-106561Y612263D01*
X-107249Y612394D01*
X-107939Y612263D01*
X-108824Y611738D01*
X-108529Y615150D01*
X-105872D01*
G01X-101343Y610557D02*
X-100654Y611476D01*
X-100064Y612000D01*
X-99276Y612263D01*
X-98587Y612000D01*
X-98095Y611476D01*
X-97701Y610688D01*
X-97603Y609769D01*
X-97701Y608982D01*
X-98095Y608194D01*
X-98686Y607538D01*
X-99374Y607276D01*
X-100162Y607538D01*
X-100851Y608326D01*
X-101245Y609507D01*
X-101343Y610819D01*
X-101146Y612525D01*
X-100851Y613444D01*
X-100359Y614363D01*
X-99670Y615019D01*
X-98981Y615150D01*
X-98292Y614888D01*
X-97800Y614231D01*
G01X-91598Y607014D02*
X-91795Y607145D01*
Y607407D01*
X-91598Y607538D01*
X-91401Y607407D01*
Y607145D01*
X-91598Y607014D01*
G01X-83723Y615150D02*
X-84511Y614888D01*
X-85101Y614231D01*
X-85495Y613444D01*
X-85790Y612394D01*
X-85889Y611213D01*
X-85790Y610032D01*
X-85495Y608982D01*
X-85101Y608194D01*
X-84511Y607538D01*
X-83723Y607276D01*
X-82936Y607538D01*
X-82345Y608194D01*
X-81951Y608982D01*
X-81656Y610032D01*
X-81557Y611213D01*
X-81656Y612394D01*
X-81951Y613444D01*
X-82345Y614231D01*
X-82936Y614888D01*
X-83723Y615150D01*
G01X-75848D02*
X-76636Y614888D01*
X-77226Y614231D01*
X-77620Y613444D01*
X-77915Y612394D01*
X-78014Y611213D01*
X-77915Y610032D01*
X-77620Y608982D01*
X-77226Y608194D01*
X-76636Y607538D01*
X-75848Y607276D01*
X-75061Y607538D01*
X-74470Y608194D01*
X-74076Y608982D01*
X-73781Y610032D01*
X-73682Y611213D01*
X-73781Y612394D01*
X-74076Y613444D01*
X-74470Y614231D01*
X-75061Y614888D01*
X-75848Y615150D01*
G01X-115721Y669221D02*
Y677095D01*
X-116902Y675520D01*
G01Y669221D02*
X-114540D01*
G01X-108043D02*
X-107846Y670927D01*
X-107551Y672370D01*
X-107157Y673683D01*
X-106665Y675126D01*
X-105877Y677095D01*
X-109815D01*
G01X-99971Y669221D02*
Y677095D01*
X-101152Y675520D01*
G01Y669221D02*
X-98790D01*
G01X-92096Y668959D02*
X-92293Y669090D01*
Y669352D01*
X-92096Y669483D01*
X-91899Y669352D01*
Y669090D01*
X-92096Y668959D01*
G01X-84221Y677095D02*
X-85009Y676833D01*
X-85599Y676176D01*
X-85993Y675389D01*
X-86288Y674339D01*
X-86387Y673158D01*
X-86288Y671977D01*
X-85993Y670927D01*
X-85599Y670139D01*
X-85009Y669483D01*
X-84221Y669221D01*
X-83434Y669483D01*
X-82843Y670139D01*
X-82449Y670927D01*
X-82154Y671977D01*
X-82055Y673158D01*
X-82154Y674339D01*
X-82449Y675389D01*
X-82843Y676176D01*
X-83434Y676833D01*
X-84221Y677095D01*
G01X-76346D02*
X-77134Y676833D01*
X-77724Y676176D01*
X-78118Y675389D01*
X-78413Y674339D01*
X-78512Y673158D01*
X-78413Y671977D01*
X-78118Y670927D01*
X-77724Y670139D01*
X-77134Y669483D01*
X-76346Y669221D01*
X-75559Y669483D01*
X-74968Y670139D01*
X-74574Y670927D01*
X-74279Y671977D01*
X-74180Y673158D01*
X-74279Y674339D01*
X-74574Y675389D01*
X-74968Y676176D01*
X-75559Y676833D01*
X-76346Y677095D01*
G01X-118425Y657760D02*
Y665634D01*
X-119606Y664059D01*
G01Y657760D02*
X-117244D01*
G01X-112420Y661041D02*
X-111731Y661960D01*
X-111141Y662484D01*
X-110353Y662747D01*
X-109664Y662484D01*
X-109172Y661960D01*
X-108778Y661172D01*
X-108680Y660253D01*
X-108778Y659466D01*
X-109172Y658678D01*
X-109763Y658022D01*
X-110451Y657760D01*
X-111239Y658022D01*
X-111928Y658810D01*
X-112322Y659991D01*
X-112420Y661303D01*
X-112223Y663009D01*
X-111928Y663928D01*
X-111436Y664847D01*
X-110747Y665503D01*
X-110058Y665634D01*
X-109369Y665372D01*
X-108877Y664715D01*
G01X-104348Y658678D02*
X-103659Y658022D01*
X-102872Y657760D01*
X-102084Y658022D01*
X-101395Y658810D01*
X-100903Y659991D01*
X-100706Y661172D01*
Y662616D01*
X-100903Y663797D01*
X-101395Y664847D01*
X-101986Y665372D01*
X-102675Y665634D01*
X-103463Y665372D01*
X-104053Y664847D01*
X-104447Y664059D01*
X-104644Y663009D01*
X-104447Y662091D01*
X-103955Y661172D01*
X-103364Y660647D01*
X-102675Y660516D01*
X-101888Y660778D01*
X-101297Y661434D01*
X-100706Y662616D01*
G01X-94800Y657498D02*
X-94997Y657629D01*
Y657891D01*
X-94800Y658022D01*
X-94603Y657891D01*
Y657629D01*
X-94800Y657498D01*
G01X-86925Y665634D02*
X-87713Y665372D01*
X-88303Y664715D01*
X-88697Y663928D01*
X-88992Y662878D01*
X-89091Y661697D01*
X-88992Y660516D01*
X-88697Y659466D01*
X-88303Y658678D01*
X-87713Y658022D01*
X-86925Y657760D01*
X-86138Y658022D01*
X-85547Y658678D01*
X-85153Y659466D01*
X-84858Y660516D01*
X-84759Y661697D01*
X-84858Y662878D01*
X-85153Y663928D01*
X-85547Y664715D01*
X-86138Y665372D01*
X-86925Y665634D01*
G01X-79050D02*
X-79838Y665372D01*
X-80428Y664715D01*
X-80822Y663928D01*
X-81117Y662878D01*
X-81216Y661697D01*
X-81117Y660516D01*
X-80822Y659466D01*
X-80428Y658678D01*
X-79838Y658022D01*
X-79050Y657760D01*
X-78263Y658022D01*
X-77672Y658678D01*
X-77278Y659466D01*
X-76983Y660516D01*
X-76884Y661697D01*
X-76983Y662878D01*
X-77278Y663928D01*
X-77672Y664715D01*
X-78263Y665372D01*
X-79050Y665634D01*
G01X-118425Y741225D02*
Y749099D01*
X-119606Y747524D01*
G01Y741225D02*
X-117244D01*
G01X-112223Y742143D02*
X-111534Y741487D01*
X-110747Y741225D01*
X-109959Y741487D01*
X-109270Y742275D01*
X-108778Y743456D01*
X-108581Y744637D01*
Y746081D01*
X-108778Y747262D01*
X-109270Y748312D01*
X-109861Y748837D01*
X-110550Y749099D01*
X-111338Y748837D01*
X-111928Y748312D01*
X-112322Y747524D01*
X-112519Y746474D01*
X-112322Y745556D01*
X-111830Y744637D01*
X-111239Y744112D01*
X-110550Y743981D01*
X-109763Y744243D01*
X-109172Y744899D01*
X-108581Y746081D01*
G01X-102675Y749099D02*
X-103463Y748837D01*
X-104053Y748180D01*
X-104447Y747393D01*
X-104742Y746343D01*
X-104841Y745162D01*
X-104742Y743981D01*
X-104447Y742931D01*
X-104053Y742143D01*
X-103463Y741487D01*
X-102675Y741225D01*
X-101888Y741487D01*
X-101297Y742143D01*
X-100903Y742931D01*
X-100608Y743981D01*
X-100509Y745162D01*
X-100608Y746343D01*
X-100903Y747393D01*
X-101297Y748180D01*
X-101888Y748837D01*
X-102675Y749099D01*
G01X-94800Y740963D02*
X-94997Y741094D01*
Y741356D01*
X-94800Y741487D01*
X-94603Y741356D01*
Y741094D01*
X-94800Y740963D01*
G01X-88795Y747787D02*
X-88205Y748574D01*
X-87516Y748968D01*
X-86728Y749099D01*
X-85744Y748837D01*
X-85055Y748180D01*
X-84858Y747393D01*
X-84956Y746605D01*
X-85350Y745949D01*
X-87319Y744637D01*
X-88205Y743718D01*
X-88795Y742406D01*
X-88992Y741225D01*
X-84858D01*
G01X-79050Y749099D02*
X-79838Y748837D01*
X-80428Y748180D01*
X-80822Y747393D01*
X-81117Y746343D01*
X-81216Y745162D01*
X-81117Y743981D01*
X-80822Y742931D01*
X-80428Y742143D01*
X-79838Y741487D01*
X-79050Y741225D01*
X-78263Y741487D01*
X-77672Y742143D01*
X-77278Y742931D01*
X-76983Y743981D01*
X-76884Y745162D01*
X-76983Y746343D01*
X-77278Y747393D01*
X-77672Y748180D01*
X-78263Y748837D01*
X-79050Y749099D01*
G01X-118425Y716815D02*
Y724689D01*
X-119606Y723114D01*
G01Y716815D02*
X-117244D01*
G01X-110550D02*
X-109861Y716946D01*
X-109074Y717340D01*
X-108581Y717996D01*
X-108384Y718915D01*
X-108581Y719833D01*
X-109172Y720621D01*
X-110058Y721015D01*
X-111042D01*
X-111633Y721277D01*
X-112125Y721933D01*
X-112322Y722852D01*
X-112026Y723770D01*
X-111338Y724427D01*
X-110550Y724689D01*
X-109763Y724427D01*
X-109074Y723770D01*
X-108778Y722852D01*
X-108975Y721933D01*
X-109467Y721277D01*
X-110058Y721015D01*
X-111042D01*
X-111928Y720621D01*
X-112519Y719833D01*
X-112716Y718915D01*
X-112519Y717996D01*
X-112026Y717340D01*
X-111239Y716946D01*
X-110550Y716815D01*
G01X-101494D02*
Y724689D01*
X-105136Y719046D01*
X-100214D01*
G01X-94800Y716553D02*
X-94997Y716684D01*
Y716946D01*
X-94800Y717077D01*
X-94603Y716946D01*
Y716684D01*
X-94800Y716553D01*
G01X-86925Y724689D02*
X-87713Y724427D01*
X-88303Y723770D01*
X-88697Y722983D01*
X-88992Y721933D01*
X-89091Y720752D01*
X-88992Y719571D01*
X-88697Y718521D01*
X-88303Y717733D01*
X-87713Y717077D01*
X-86925Y716815D01*
X-86138Y717077D01*
X-85547Y717733D01*
X-85153Y718521D01*
X-84858Y719571D01*
X-84759Y720752D01*
X-84858Y721933D01*
X-85153Y722983D01*
X-85547Y723770D01*
X-86138Y724427D01*
X-86925Y724689D01*
G01X-79050D02*
X-79838Y724427D01*
X-80428Y723770D01*
X-80822Y722983D01*
X-81117Y721933D01*
X-81216Y720752D01*
X-81117Y719571D01*
X-80822Y718521D01*
X-80428Y717733D01*
X-79838Y717077D01*
X-79050Y716815D01*
X-78263Y717077D01*
X-77672Y717733D01*
X-77278Y718521D01*
X-76983Y719571D01*
X-76884Y720752D01*
X-76983Y721933D01*
X-77278Y722983D01*
X-77672Y723770D01*
X-78263Y724427D01*
X-79050Y724689D01*
G01X-119967Y811887D02*
X-119377Y812674D01*
X-118688Y813068D01*
X-117900Y813199D01*
X-116916Y812937D01*
X-116227Y812280D01*
X-116030Y811493D01*
X-116128Y810705D01*
X-116522Y810049D01*
X-118491Y808737D01*
X-119377Y807818D01*
X-119967Y806506D01*
X-120164Y805325D01*
X-116030D01*
G01X-110222Y813199D02*
X-111010Y812937D01*
X-111600Y812280D01*
X-111994Y811493D01*
X-112289Y810443D01*
X-112388Y809262D01*
X-112289Y808081D01*
X-111994Y807031D01*
X-111600Y806243D01*
X-111010Y805587D01*
X-110222Y805325D01*
X-109435Y805587D01*
X-108844Y806243D01*
X-108450Y807031D01*
X-108155Y808081D01*
X-108056Y809262D01*
X-108155Y810443D01*
X-108450Y811493D01*
X-108844Y812280D01*
X-109435Y812937D01*
X-110222Y813199D01*
G01X-104513Y806506D02*
X-103922Y805850D01*
X-103233Y805456D01*
X-102347Y805325D01*
X-101461Y805587D01*
X-100772Y806112D01*
X-100280Y807031D01*
X-100181Y808081D01*
X-100378Y809131D01*
X-100871Y809787D01*
X-101560Y810312D01*
X-102248Y810443D01*
X-102938Y810312D01*
X-103823Y809787D01*
X-103528Y813199D01*
X-100871D01*
G01X-94472Y805063D02*
X-94669Y805194D01*
Y805456D01*
X-94472Y805587D01*
X-94275Y805456D01*
Y805194D01*
X-94472Y805063D01*
G01X-88467Y811887D02*
X-87877Y812674D01*
X-87188Y813068D01*
X-86400Y813199D01*
X-85416Y812937D01*
X-84727Y812280D01*
X-84530Y811493D01*
X-84628Y810705D01*
X-85022Y810049D01*
X-86991Y808737D01*
X-87877Y807818D01*
X-88467Y806506D01*
X-88664Y805325D01*
X-84530D01*
G01X-78722Y813199D02*
X-79510Y812937D01*
X-80100Y812280D01*
X-80494Y811493D01*
X-80789Y810443D01*
X-80888Y809262D01*
X-80789Y808081D01*
X-80494Y807031D01*
X-80100Y806243D01*
X-79510Y805587D01*
X-78722Y805325D01*
X-77935Y805587D01*
X-77344Y806243D01*
X-76950Y807031D01*
X-76655Y808081D01*
X-76556Y809262D01*
X-76655Y810443D01*
X-76950Y811493D01*
X-77344Y812280D01*
X-77935Y812937D01*
X-78722Y813199D01*
G01X-118465Y799247D02*
X-117875Y800034D01*
X-117186Y800428D01*
X-116398Y800559D01*
X-115414Y800297D01*
X-114725Y799640D01*
X-114528Y798853D01*
X-114626Y798065D01*
X-115020Y797409D01*
X-116989Y796097D01*
X-117875Y795178D01*
X-118465Y793866D01*
X-118662Y792685D01*
X-114528D01*
G01X-108720Y800559D02*
X-109508Y800297D01*
X-110098Y799640D01*
X-110492Y798853D01*
X-110787Y797803D01*
X-110886Y796622D01*
X-110787Y795441D01*
X-110492Y794391D01*
X-110098Y793603D01*
X-109508Y792947D01*
X-108720Y792685D01*
X-107933Y792947D01*
X-107342Y793603D01*
X-106948Y794391D01*
X-106653Y795441D01*
X-106554Y796622D01*
X-106653Y797803D01*
X-106948Y798853D01*
X-107342Y799640D01*
X-107933Y800297D01*
X-108720Y800559D01*
G01X-103011Y794260D02*
X-102420Y793341D01*
X-101633Y792816D01*
X-100746Y792685D01*
X-99959Y792816D01*
X-99172Y793472D01*
X-98679Y794260D01*
X-98581Y795047D01*
X-98778Y795966D01*
X-99467Y796622D01*
X-100156Y796885D01*
X-101042D01*
G01X-100156D02*
X-99565Y797278D01*
X-99073Y797934D01*
X-98876Y798722D01*
X-99073Y799509D01*
X-99565Y800165D01*
X-100451Y800559D01*
X-101337Y800428D01*
X-102223Y799903D01*
G01X-92970Y792423D02*
X-93167Y792554D01*
Y792816D01*
X-92970Y792947D01*
X-92773Y792816D01*
Y792554D01*
X-92970Y792423D01*
G01X-86965Y799247D02*
X-86375Y800034D01*
X-85686Y800428D01*
X-84898Y800559D01*
X-83914Y800297D01*
X-83225Y799640D01*
X-83028Y798853D01*
X-83126Y798065D01*
X-83520Y797409D01*
X-85489Y796097D01*
X-86375Y795178D01*
X-86965Y793866D01*
X-87162Y792685D01*
X-83028D01*
G01X-77220Y800559D02*
X-78008Y800297D01*
X-78598Y799640D01*
X-78992Y798853D01*
X-79287Y797803D01*
X-79386Y796622D01*
X-79287Y795441D01*
X-78992Y794391D01*
X-78598Y793603D01*
X-78008Y792947D01*
X-77220Y792685D01*
X-76433Y792947D01*
X-75842Y793603D01*
X-75448Y794391D01*
X-75153Y795441D01*
X-75054Y796622D01*
X-75153Y797803D01*
X-75448Y798853D01*
X-75842Y799640D01*
X-76433Y800297D01*
X-77220Y800559D01*
G01X-119778Y882712D02*
X-119188Y883499D01*
X-118499Y883893D01*
X-117711Y884024D01*
X-116727Y883762D01*
X-116038Y883105D01*
X-115841Y882318D01*
X-115939Y881530D01*
X-116333Y880874D01*
X-118302Y879562D01*
X-119188Y878643D01*
X-119778Y877331D01*
X-119975Y876150D01*
X-115841D01*
G01X-111903Y882712D02*
X-111313Y883499D01*
X-110624Y883893D01*
X-109836Y884024D01*
X-108852Y883762D01*
X-108163Y883105D01*
X-107966Y882318D01*
X-108064Y881530D01*
X-108458Y880874D01*
X-110427Y879562D01*
X-111313Y878643D01*
X-111903Y877331D01*
X-112100Y876150D01*
X-107966D01*
G01X-100977D02*
Y884024D01*
X-104619Y878381D01*
X-99697D01*
G01X-94283Y875888D02*
X-94480Y876019D01*
Y876281D01*
X-94283Y876412D01*
X-94086Y876281D01*
Y876019D01*
X-94283Y875888D01*
G01X-85227Y876150D02*
Y884024D01*
X-88869Y878381D01*
X-83947D01*
G01X-78533Y884024D02*
X-79321Y883762D01*
X-79911Y883105D01*
X-80305Y882318D01*
X-80600Y881268D01*
X-80699Y880087D01*
X-80600Y878906D01*
X-80305Y877856D01*
X-79911Y877068D01*
X-79321Y876412D01*
X-78533Y876150D01*
X-77746Y876412D01*
X-77155Y877068D01*
X-76761Y877856D01*
X-76466Y878906D01*
X-76367Y880087D01*
X-76466Y881268D01*
X-76761Y882318D01*
X-77155Y883105D01*
X-77746Y883762D01*
X-78533Y884024D01*
G01X-117153Y858302D02*
X-116563Y859089D01*
X-115874Y859483D01*
X-115086Y859614D01*
X-114102Y859352D01*
X-113413Y858695D01*
X-113216Y857908D01*
X-113314Y857120D01*
X-113708Y856464D01*
X-115677Y855152D01*
X-116563Y854233D01*
X-117153Y852921D01*
X-117350Y851740D01*
X-113216D01*
G01X-107408D02*
Y859614D01*
X-108589Y858039D01*
G01Y851740D02*
X-106227D01*
G01X-99533D02*
X-98844Y851871D01*
X-98057Y852265D01*
X-97564Y852921D01*
X-97367Y853840D01*
X-97564Y854758D01*
X-98155Y855546D01*
X-99041Y855940D01*
X-100025D01*
X-100616Y856202D01*
X-101108Y856858D01*
X-101305Y857777D01*
X-101009Y858695D01*
X-100321Y859352D01*
X-99533Y859614D01*
X-98746Y859352D01*
X-98057Y858695D01*
X-97761Y857777D01*
X-97958Y856858D01*
X-98450Y856202D01*
X-99041Y855940D01*
X-100025D01*
X-100911Y855546D01*
X-101502Y854758D01*
X-101699Y853840D01*
X-101502Y852921D01*
X-101009Y852265D01*
X-100222Y851871D01*
X-99533Y851740D01*
G01X-91658Y851478D02*
X-91855Y851609D01*
Y851871D01*
X-91658Y852002D01*
X-91461Y851871D01*
Y851609D01*
X-91658Y851478D01*
G01X-85653Y858302D02*
X-85063Y859089D01*
X-84374Y859483D01*
X-83586Y859614D01*
X-82602Y859352D01*
X-81913Y858695D01*
X-81716Y857908D01*
X-81814Y857120D01*
X-82208Y856464D01*
X-84177Y855152D01*
X-85063Y854233D01*
X-85653Y852921D01*
X-85850Y851740D01*
X-81716D01*
G01X-75908Y859614D02*
X-76696Y859352D01*
X-77286Y858695D01*
X-77680Y857908D01*
X-77975Y856858D01*
X-78074Y855677D01*
X-77975Y854496D01*
X-77680Y853446D01*
X-77286Y852658D01*
X-76696Y852002D01*
X-75908Y851740D01*
X-75121Y852002D01*
X-74530Y852658D01*
X-74136Y853446D01*
X-73841Y854496D01*
X-73742Y855677D01*
X-73841Y856858D01*
X-74136Y857908D01*
X-74530Y858695D01*
X-75121Y859352D01*
X-75908Y859614D01*
G01X-118011Y933157D02*
X-117421Y933944D01*
X-116732Y934338D01*
X-115944Y934469D01*
X-114960Y934207D01*
X-114271Y933550D01*
X-114074Y932763D01*
X-114172Y931975D01*
X-114566Y931319D01*
X-116535Y930007D01*
X-117421Y929088D01*
X-118011Y927776D01*
X-118208Y926595D01*
X-114074D01*
G01X-110432Y928170D02*
X-109841Y927251D01*
X-109054Y926726D01*
X-108167Y926595D01*
X-107380Y926726D01*
X-106593Y927382D01*
X-106100Y928170D01*
X-106002Y928957D01*
X-106199Y929876D01*
X-106888Y930532D01*
X-107577Y930795D01*
X-108463D01*
G01X-107577D02*
X-106986Y931188D01*
X-106494Y931844D01*
X-106297Y932632D01*
X-106494Y933419D01*
X-106986Y934075D01*
X-107872Y934469D01*
X-108758Y934338D01*
X-109644Y933813D01*
G01X-100588Y926595D02*
X-100391Y928301D01*
X-100096Y929744D01*
X-99702Y931057D01*
X-99210Y932500D01*
X-98422Y934469D01*
X-102360D01*
G01X-92516Y926333D02*
X-92713Y926464D01*
Y926726D01*
X-92516Y926857D01*
X-92319Y926726D01*
Y926464D01*
X-92516Y926333D01*
G01X-83460Y926595D02*
Y934469D01*
X-87102Y928826D01*
X-82180D01*
G01X-76766Y934469D02*
X-77554Y934207D01*
X-78144Y933550D01*
X-78538Y932763D01*
X-78833Y931713D01*
X-78932Y930532D01*
X-78833Y929351D01*
X-78538Y928301D01*
X-78144Y927513D01*
X-77554Y926857D01*
X-76766Y926595D01*
X-75979Y926857D01*
X-75388Y927513D01*
X-74994Y928301D01*
X-74699Y929351D01*
X-74600Y930532D01*
X-74699Y931713D01*
X-74994Y932763D01*
X-75388Y933550D01*
X-75979Y934207D01*
X-76766Y934469D01*
G01X-145015Y1553786D02*
X-144129Y1554966D01*
X-143096Y1555557D01*
X-141915Y1555754D01*
X-140438Y1555360D01*
X-139405Y1554376D01*
X-139110Y1553195D01*
X-139257Y1552014D01*
X-139848Y1551030D01*
X-142801Y1549061D01*
X-144129Y1547683D01*
X-145015Y1545714D01*
X-145310Y1543943D01*
X-139110D01*
G01X-3937Y968195D02*
X-3675Y967407D01*
X-3018Y966817D01*
X-2231Y966423D01*
X-1181Y966128D01*
X0Y966029D01*
X1181Y966128D01*
X2231Y966423D01*
X3019Y966817D01*
X3675Y967407D01*
X3937Y968195D01*
X3675Y968982D01*
X3019Y969573D01*
X2231Y969967D01*
X1181Y970262D01*
X0Y970361D01*
X-1181Y970262D01*
X-2231Y969967D01*
X-3018Y969573D01*
X-3675Y968982D01*
X-3937Y968195D01*
G01X4199Y976070D02*
X4068Y975873D01*
X3806D01*
X3675Y976070D01*
X3806Y976267D01*
X4068D01*
X4199Y976070D01*
G01X-3937Y983945D02*
X-3675Y983157D01*
X-3018Y982567D01*
X-2231Y982173D01*
X-1181Y981878D01*
X0Y981779D01*
X1181Y981878D01*
X2231Y982173D01*
X3019Y982567D01*
X3675Y983157D01*
X3937Y983945D01*
X3675Y984732D01*
X3019Y985323D01*
X2231Y985717D01*
X1181Y986012D01*
X0Y986111D01*
X-1181Y986012D01*
X-2231Y985717D01*
X-3018Y985323D01*
X-3675Y984732D01*
X-3937Y983945D01*
G01Y991820D02*
X-3675Y991032D01*
X-3018Y990442D01*
X-2231Y990048D01*
X-1181Y989753D01*
X0Y989654D01*
X1181Y989753D01*
X2231Y990048D01*
X3019Y990442D01*
X3675Y991032D01*
X3937Y991820D01*
X3675Y992607D01*
X3019Y993198D01*
X2231Y993592D01*
X1181Y993887D01*
X0Y993986D01*
X-1181Y993887D01*
X-2231Y993592D01*
X-3018Y993198D01*
X-3675Y992607D01*
X-3937Y991820D01*
G01X74211Y-631451D02*
X75097Y-632829D01*
X76278Y-633616D01*
X77607Y-633813D01*
X78788Y-633616D01*
X79969Y-632632D01*
X80707Y-631451D01*
X80855Y-630270D01*
X80559Y-628892D01*
X79526Y-627908D01*
X78492Y-627514D01*
X77164D01*
G01X78492D02*
X79378Y-626923D01*
X80117Y-625939D01*
X80412Y-624758D01*
X80117Y-623577D01*
X79378Y-622593D01*
X78050Y-622002D01*
X76721Y-622199D01*
X75392Y-622986D01*
G01X70104Y-24451D02*
X70891Y-25107D01*
X71777Y-25501D01*
X72565D01*
X73352Y-25107D01*
X73943Y-24451D01*
X74238Y-23532D01*
X74041Y-22614D01*
X73549Y-21827D01*
X72663Y-21301D01*
X71482Y-21039D01*
X70793Y-20514D01*
X70498Y-19596D01*
X70695Y-18677D01*
X71187Y-18021D01*
X71876Y-17627D01*
X72565D01*
X73254Y-17889D01*
X73844Y-18546D01*
G01X78570Y-21958D02*
X81719D01*
X81424Y-21039D01*
X80932Y-20514D01*
X80243Y-20252D01*
X79554Y-20383D01*
X78963Y-20777D01*
X78570Y-21695D01*
X78373Y-22483D01*
Y-23270D01*
X78570Y-24058D01*
X79062Y-24845D01*
X79652Y-25370D01*
X80341Y-25501D01*
X81030Y-25239D01*
X81719Y-24451D01*
G01X86543Y-25501D02*
Y-20252D01*
G01Y-21301D02*
X87035Y-20777D01*
X87527Y-20383D01*
X88216Y-20252D01*
X88708Y-20383D01*
X89299Y-20777D01*
G01X95796Y-20252D02*
Y-25501D01*
G01Y-18152D02*
X95599Y-18021D01*
Y-17758D01*
X95796Y-17627D01*
X95993Y-17758D01*
Y-18021D01*
X95796Y-18152D01*
G01X105443Y-25501D02*
Y-20252D01*
G01Y-21170D02*
X105049Y-20645D01*
X104458Y-20383D01*
X103770Y-20252D01*
X103080Y-20514D01*
X102490Y-21039D01*
X102096Y-21827D01*
X101899Y-22876D01*
X102096Y-23926D01*
X102490Y-24714D01*
X103080Y-25239D01*
X103770Y-25501D01*
X104458Y-25370D01*
X105049Y-24976D01*
X105443Y-24451D01*
G01X111546Y-25501D02*
Y-17627D01*
G01X125623Y-25501D02*
Y-20252D01*
G01Y-21564D02*
X126016Y-20908D01*
X126607Y-20383D01*
X127395Y-20252D01*
X128083Y-20383D01*
X128674Y-20908D01*
X128969Y-21827D01*
Y-25501D01*
G01X133498Y-20252D02*
Y-23926D01*
X133891Y-24845D01*
X134482Y-25370D01*
X135171Y-25501D01*
X135860Y-25370D01*
X136451Y-24845D01*
X136844Y-23926D01*
G01Y-25501D02*
Y-20252D01*
G01X140093Y-25501D02*
Y-20252D01*
G01Y-21695D02*
X140388Y-21039D01*
X140880Y-20514D01*
X141570Y-20252D01*
X142258Y-20514D01*
X142751Y-21039D01*
X143046Y-21695D01*
Y-25501D01*
G01Y-21695D02*
X143341Y-21039D01*
X143833Y-20514D01*
X144522Y-20252D01*
X145212Y-20514D01*
X145704Y-21039D01*
X145999Y-21827D01*
Y-25501D01*
G01X149149D02*
Y-17627D01*
G01Y-21564D02*
X149641Y-20777D01*
X150232Y-20383D01*
X150822Y-20252D01*
X151708Y-20514D01*
X152299Y-21039D01*
X152693Y-21958D01*
Y-23008D01*
X152496Y-24058D01*
X152102Y-24845D01*
X151413Y-25370D01*
X150822Y-25501D01*
X150232Y-25370D01*
X149641Y-24976D01*
X149149Y-24320D01*
G01X157320Y-21958D02*
X160469D01*
X160174Y-21039D01*
X159682Y-20514D01*
X158993Y-20252D01*
X158304Y-20383D01*
X157713Y-20777D01*
X157320Y-21695D01*
X157123Y-22483D01*
Y-23270D01*
X157320Y-24058D01*
X157812Y-24845D01*
X158402Y-25370D01*
X159091Y-25501D01*
X159780Y-25239D01*
X160469Y-24451D01*
G01X165293Y-25501D02*
Y-20252D01*
G01Y-21301D02*
X165785Y-20777D01*
X166277Y-20383D01*
X166966Y-20252D01*
X167458Y-20383D01*
X168049Y-20777D01*
G01X184193Y-25501D02*
Y-20252D01*
G01Y-21170D02*
X183799Y-20645D01*
X183208Y-20383D01*
X182520Y-20252D01*
X181830Y-20514D01*
X181240Y-21039D01*
X180846Y-21827D01*
X180649Y-22876D01*
X180846Y-23926D01*
X181240Y-24714D01*
X181830Y-25239D01*
X182520Y-25501D01*
X183208Y-25370D01*
X183799Y-24976D01*
X184193Y-24451D01*
G01X188623Y-25501D02*
Y-20252D01*
G01Y-21564D02*
X189016Y-20908D01*
X189607Y-20383D01*
X190395Y-20252D01*
X191083Y-20383D01*
X191674Y-20908D01*
X191969Y-21827D01*
Y-25501D01*
G01X199943Y-17627D02*
Y-25501D01*
G01Y-24320D02*
X199549Y-24976D01*
X198958Y-25370D01*
X198270Y-25501D01*
X197482Y-25239D01*
X196891Y-24583D01*
X196498Y-23795D01*
X196399Y-22876D01*
X196498Y-21958D01*
X196891Y-21170D01*
X197482Y-20514D01*
X198270Y-20252D01*
X198958Y-20383D01*
X199451Y-20645D01*
X199943Y-21170D01*
G01X212543Y-25501D02*
Y-20252D01*
G01Y-21301D02*
X213035Y-20777D01*
X213527Y-20383D01*
X214216Y-20252D01*
X214708Y-20383D01*
X215299Y-20777D01*
G01X220320Y-21958D02*
X223469D01*
X223174Y-21039D01*
X222682Y-20514D01*
X221993Y-20252D01*
X221304Y-20383D01*
X220713Y-20777D01*
X220320Y-21695D01*
X220123Y-22483D01*
Y-23270D01*
X220320Y-24058D01*
X220812Y-24845D01*
X221402Y-25370D01*
X222091Y-25501D01*
X222780Y-25239D01*
X223469Y-24451D01*
G01X229080Y-25501D02*
Y-18808D01*
X229277Y-18152D01*
X229671Y-17758D01*
X230262Y-17627D01*
X230852Y-17889D01*
X231147Y-18546D01*
G01X229966Y-20777D02*
X227998D01*
G01X236070Y-21958D02*
X239219D01*
X238924Y-21039D01*
X238432Y-20514D01*
X237743Y-20252D01*
X237054Y-20383D01*
X236463Y-20777D01*
X236070Y-21695D01*
X235873Y-22483D01*
Y-23270D01*
X236070Y-24058D01*
X236562Y-24845D01*
X237152Y-25370D01*
X237841Y-25501D01*
X238530Y-25239D01*
X239219Y-24451D01*
G01X244043Y-25501D02*
Y-20252D01*
G01Y-21301D02*
X244535Y-20777D01*
X245027Y-20383D01*
X245716Y-20252D01*
X246208Y-20383D01*
X246799Y-20777D01*
G01X251820Y-21958D02*
X254969D01*
X254674Y-21039D01*
X254182Y-20514D01*
X253493Y-20252D01*
X252804Y-20383D01*
X252213Y-20777D01*
X251820Y-21695D01*
X251623Y-22483D01*
Y-23270D01*
X251820Y-24058D01*
X252312Y-24845D01*
X252902Y-25370D01*
X253591Y-25501D01*
X254280Y-25239D01*
X254969Y-24451D01*
G01X259498Y-25501D02*
Y-20252D01*
G01Y-21564D02*
X259891Y-20908D01*
X260482Y-20383D01*
X261270Y-20252D01*
X261958Y-20383D01*
X262549Y-20908D01*
X262844Y-21827D01*
Y-25501D01*
G01X270621Y-20908D02*
X269932Y-20383D01*
X269341Y-20252D01*
X268554Y-20514D01*
X267963Y-21039D01*
X267570Y-21958D01*
X267471Y-22876D01*
X267570Y-23795D01*
X267963Y-24583D01*
X268554Y-25239D01*
X269341Y-25501D01*
X270030Y-25239D01*
X270621Y-24714D01*
G01X275445Y-21958D02*
X278594D01*
X278299Y-21039D01*
X277807Y-20514D01*
X277118Y-20252D01*
X276429Y-20383D01*
X275838Y-20777D01*
X275445Y-21695D01*
X275248Y-22483D01*
Y-23270D01*
X275445Y-24058D01*
X275937Y-24845D01*
X276527Y-25370D01*
X277216Y-25501D01*
X277905Y-25239D01*
X278594Y-24451D01*
G01X292671Y-25501D02*
X292080Y-25370D01*
X291490Y-24845D01*
X291096Y-23926D01*
X290899Y-22876D01*
X291096Y-21827D01*
X291490Y-20908D01*
X292080Y-20383D01*
X292671Y-20252D01*
X293262Y-20383D01*
X293852Y-20908D01*
X294246Y-21827D01*
X294344Y-22876D01*
X294246Y-23926D01*
X293852Y-24845D01*
X293262Y-25370D01*
X292671Y-25501D01*
G01X298873D02*
Y-20252D01*
G01Y-21564D02*
X299266Y-20908D01*
X299857Y-20383D01*
X300645Y-20252D01*
X301333Y-20383D01*
X301924Y-20908D01*
X302219Y-21827D01*
Y-25501D01*
G01X308421D02*
Y-17627D01*
G01X314229Y-27863D02*
X314820Y-28126D01*
X315607Y-27863D01*
X316099Y-27338D01*
X316493Y-26682D01*
X317083Y-24583D01*
X318363Y-20252D01*
G01X315213D02*
X317083Y-24583D01*
G01X324171Y-25763D02*
X323974Y-25632D01*
Y-25370D01*
X324171Y-25239D01*
X324368Y-25370D01*
Y-25632D01*
X324171Y-25763D01*
G01X76576Y968195D02*
X68702D01*
X70277Y967014D01*
G01X76576D02*
Y969376D01*
G01Y976070D02*
X76445Y976759D01*
X76051Y977546D01*
X75395Y978039D01*
X74476Y978236D01*
X73558Y978039D01*
X72770Y977448D01*
X72376Y976562D01*
Y975578D01*
X72114Y974987D01*
X71458Y974495D01*
X70539Y974298D01*
X69621Y974594D01*
X68964Y975282D01*
X68702Y976070D01*
X68964Y976857D01*
X69621Y977546D01*
X70539Y977842D01*
X71458Y977645D01*
X72114Y977153D01*
X72376Y976562D01*
Y975578D01*
X72770Y974692D01*
X73558Y974101D01*
X74476Y973904D01*
X75395Y974101D01*
X76051Y974594D01*
X76445Y975381D01*
X76576Y976070D01*
G01X76838Y983945D02*
X76707Y983748D01*
X76445D01*
X76314Y983945D01*
X76445Y984142D01*
X76707D01*
X76838Y983945D01*
G01X76576Y993001D02*
X68702D01*
X74345Y989359D01*
Y994281D01*
G01X75395Y997529D02*
X76051Y998120D01*
X76445Y998809D01*
X76576Y999695D01*
X76314Y1000581D01*
X75789Y1001270D01*
X74870Y1001762D01*
X73820Y1001861D01*
X72770Y1001664D01*
X72114Y1001171D01*
X71589Y1000482D01*
X71458Y999794D01*
X71589Y999104D01*
X72114Y998219D01*
X68702Y998514D01*
Y1001171D01*
G01X74211Y1546305D02*
X75097Y1544927D01*
X76278Y1544140D01*
X77607Y1543943D01*
X78788Y1544140D01*
X79969Y1545124D01*
X80707Y1546305D01*
X80855Y1547486D01*
X80559Y1548864D01*
X79526Y1549848D01*
X78492Y1550242D01*
X77164D01*
G01X78492D02*
X79378Y1550833D01*
X80117Y1551817D01*
X80412Y1552998D01*
X80117Y1554179D01*
X79378Y1555163D01*
X78050Y1555754D01*
X76721Y1555557D01*
X75392Y1554770D01*
G01X298900Y-633813D02*
Y-622002D01*
X293437Y-630467D01*
X300819D01*
G01X298900Y1543943D02*
Y1555754D01*
X293437Y1547289D01*
X300819D01*
G01X363372Y23397D02*
Y7649D01*
G01X358845Y23397D02*
X367900D01*
G01X363372Y158043D02*
Y142295D01*
G01X358845Y158043D02*
X367900D01*
G01X363372Y292689D02*
Y276941D01*
G01X358845Y292689D02*
X367900D01*
G01X363372Y427335D02*
Y411587D01*
G01X358845Y427335D02*
X367900D01*
G01X363372Y561981D02*
Y546233D01*
G01X358845Y561981D02*
X367900D01*
G01X363372Y696627D02*
Y680879D01*
G01X358845Y696627D02*
X367900D01*
G01X363372Y831273D02*
Y815525D01*
G01X358845Y831273D02*
X367900D01*
G01X437613Y95501D02*
Y111249D01*
G01X442140Y95501D02*
X433085D01*
G01X437613Y230147D02*
Y245895D01*
G01X442140Y230147D02*
X433085D01*
G01X437613Y364793D02*
Y380541D01*
G01X442140Y364793D02*
X433085D01*
G01X437613Y499439D02*
Y515187D01*
G01X442140Y499439D02*
X433085D01*
G01X437613Y634085D02*
Y649833D01*
G01X442140Y634085D02*
X433085D01*
G01X437613Y768731D02*
Y784479D01*
G01X442140Y768731D02*
X433085D01*
G01X437613Y903378D02*
Y919126D01*
G01X442140Y903378D02*
X433085D01*
G01X513550Y-632042D02*
X514436Y-633026D01*
X515469Y-633616D01*
X516798Y-633813D01*
X518127Y-633419D01*
X519160Y-632632D01*
X519898Y-631254D01*
X520046Y-629679D01*
X519751Y-628104D01*
X519012Y-627120D01*
X517979Y-626333D01*
X516946Y-626136D01*
X515912Y-626333D01*
X514584Y-627120D01*
X515026Y-622002D01*
X519012D01*
G01X513550Y1545714D02*
X514436Y1544730D01*
X515469Y1544140D01*
X516798Y1543943D01*
X518127Y1544337D01*
X519160Y1545124D01*
X519898Y1546502D01*
X520046Y1548077D01*
X519751Y1549652D01*
X519012Y1550636D01*
X517979Y1551423D01*
X516946Y1551620D01*
X515912Y1551423D01*
X514584Y1550636D01*
X515026Y1555754D01*
X519012D01*
G01X733662Y-628892D02*
X734695Y-627514D01*
X735581Y-626726D01*
X736762Y-626333D01*
X737796Y-626726D01*
X738534Y-627514D01*
X739125Y-628695D01*
X739272Y-630073D01*
X739125Y-631254D01*
X738534Y-632435D01*
X737648Y-633419D01*
X736615Y-633813D01*
X735434Y-633419D01*
X734400Y-632239D01*
X733809Y-630467D01*
X733662Y-628498D01*
X733957Y-625939D01*
X734400Y-624561D01*
X735138Y-623183D01*
X736172Y-622199D01*
X737205Y-622002D01*
X738239Y-622396D01*
X738977Y-623380D01*
G01X732283Y968195D02*
X724409D01*
X725984Y967014D01*
G01X732283D02*
Y969376D01*
G01Y976070D02*
X732152Y976759D01*
X731758Y977546D01*
X731102Y978039D01*
X730183Y978236D01*
X729265Y978039D01*
X728477Y977448D01*
X728083Y976562D01*
Y975578D01*
X727821Y974987D01*
X727165Y974495D01*
X726246Y974298D01*
X725328Y974594D01*
X724671Y975282D01*
X724409Y976070D01*
X724671Y976857D01*
X725328Y977546D01*
X726246Y977842D01*
X727165Y977645D01*
X727821Y977153D01*
X728083Y976562D01*
Y975578D01*
X728477Y974692D01*
X729265Y974101D01*
X730183Y973904D01*
X731102Y974101D01*
X731758Y974594D01*
X732152Y975381D01*
X732283Y976070D01*
G01X731102Y981779D02*
X731758Y982370D01*
X732152Y983059D01*
X732283Y983945D01*
X732021Y984831D01*
X731496Y985520D01*
X730577Y986012D01*
X729527Y986111D01*
X728477Y985914D01*
X727821Y985421D01*
X727296Y984732D01*
X727165Y984044D01*
X727296Y983354D01*
X727821Y982469D01*
X724409Y982764D01*
Y985421D01*
G01X732545Y991820D02*
X732414Y991623D01*
X732152D01*
X732021Y991820D01*
X732152Y992017D01*
X732414D01*
X732545Y991820D01*
G01X724409Y999695D02*
X724671Y998907D01*
X725328Y998317D01*
X726115Y997923D01*
X727165Y997628D01*
X728346Y997529D01*
X729527Y997628D01*
X730577Y997923D01*
X731365Y998317D01*
X732021Y998907D01*
X732283Y999695D01*
X732021Y1000482D01*
X731365Y1001073D01*
X730577Y1001467D01*
X729527Y1001762D01*
X728346Y1001861D01*
X727165Y1001762D01*
X726115Y1001467D01*
X725328Y1001073D01*
X724671Y1000482D01*
X724409Y999695D01*
G01Y1007570D02*
X724671Y1006782D01*
X725328Y1006192D01*
X726115Y1005798D01*
X727165Y1005503D01*
X728346Y1005404D01*
X729527Y1005503D01*
X730577Y1005798D01*
X731365Y1006192D01*
X732021Y1006782D01*
X732283Y1007570D01*
X732021Y1008357D01*
X731365Y1008948D01*
X730577Y1009342D01*
X729527Y1009637D01*
X728346Y1009736D01*
X727165Y1009637D01*
X726115Y1009342D01*
X725328Y1008948D01*
X724671Y1008357D01*
X724409Y1007570D01*
G01X733662Y1548864D02*
X734695Y1550242D01*
X735581Y1551030D01*
X736762Y1551423D01*
X737796Y1551030D01*
X738534Y1550242D01*
X739125Y1549061D01*
X739272Y1547683D01*
X739125Y1546502D01*
X738534Y1545321D01*
X737648Y1544337D01*
X736615Y1543943D01*
X735434Y1544337D01*
X734400Y1545517D01*
X733809Y1547289D01*
X733662Y1549258D01*
X733957Y1551817D01*
X734400Y1553195D01*
X735138Y1554573D01*
X736172Y1555557D01*
X737205Y1555754D01*
X738239Y1555360D01*
X738977Y1554376D01*
G01X798360Y966325D02*
X797573Y966915D01*
X797179Y967604D01*
X797048Y968392D01*
X797310Y969376D01*
X797967Y970065D01*
X798754Y970262D01*
X799542Y970164D01*
X800198Y969770D01*
X801510Y967801D01*
X802429Y966915D01*
X803741Y966325D01*
X804922Y966128D01*
Y970262D01*
G01X797048Y976070D02*
X797310Y975282D01*
X797967Y974692D01*
X798754Y974298D01*
X799804Y974003D01*
X800985Y973904D01*
X802166Y974003D01*
X803216Y974298D01*
X804004Y974692D01*
X804660Y975282D01*
X804922Y976070D01*
X804660Y976857D01*
X804004Y977448D01*
X803216Y977842D01*
X802166Y978137D01*
X800985Y978236D01*
X799804Y978137D01*
X798754Y977842D01*
X797967Y977448D01*
X797310Y976857D01*
X797048Y976070D01*
G01X803347Y981779D02*
X804266Y982370D01*
X804791Y983157D01*
X804922Y984044D01*
X804791Y984831D01*
X804135Y985618D01*
X803347Y986111D01*
X802560Y986209D01*
X801641Y986012D01*
X800985Y985323D01*
X800722Y984634D01*
Y983748D01*
G01Y984634D02*
X800329Y985225D01*
X799673Y985717D01*
X798885Y985914D01*
X798098Y985717D01*
X797442Y985225D01*
X797048Y984339D01*
X797179Y983453D01*
X797704Y982567D01*
G01X805184Y991820D02*
X805053Y991623D01*
X804791D01*
X804660Y991820D01*
X804791Y992017D01*
X805053D01*
X805184Y991820D01*
G01X804922Y1000876D02*
X797048D01*
X802691Y997234D01*
Y1002156D01*
G01X803741Y1005404D02*
X804397Y1005995D01*
X804791Y1006684D01*
X804922Y1007570D01*
X804660Y1008456D01*
X804135Y1009145D01*
X803216Y1009637D01*
X802166Y1009736D01*
X801116Y1009539D01*
X800460Y1009046D01*
X799935Y1008357D01*
X799804Y1007669D01*
X799935Y1006979D01*
X800460Y1006094D01*
X797048Y1006389D01*
Y1009046D01*
G01X810275Y40544D02*
Y45544D01*
X812681D01*
G01X811795Y43127D02*
X810275D01*
G01X816578Y43877D02*
Y40544D01*
G01Y45211D02*
X816451Y45294D01*
Y45461D01*
X816578Y45544D01*
X816705Y45461D01*
Y45294D01*
X816578Y45211D01*
G01X822818Y45544D02*
Y40544D01*
G01Y41294D02*
X822565Y40877D01*
X822185Y40627D01*
X821741Y40544D01*
X821235Y40711D01*
X820855Y41127D01*
X820601Y41627D01*
X820538Y42211D01*
X820601Y42794D01*
X820855Y43294D01*
X821235Y43711D01*
X821741Y43877D01*
X822185Y43794D01*
X822501Y43627D01*
X822818Y43294D01*
G01X825701Y43877D02*
Y41544D01*
X825955Y40961D01*
X826335Y40627D01*
X826778Y40544D01*
X827221Y40627D01*
X827601Y40961D01*
X827855Y41544D01*
G01Y40544D02*
Y43877D01*
G01X832891Y43461D02*
X832448Y43794D01*
X832068Y43877D01*
X831561Y43711D01*
X831181Y43377D01*
X830928Y42794D01*
X830865Y42211D01*
X830928Y41627D01*
X831181Y41127D01*
X831561Y40711D01*
X832068Y40544D01*
X832511Y40711D01*
X832891Y41044D01*
G01X836978Y43877D02*
Y40544D01*
G01Y45211D02*
X836851Y45294D01*
Y45461D01*
X836978Y45544D01*
X837105Y45461D01*
Y45294D01*
X836978Y45211D01*
G01X843218Y40544D02*
Y43877D01*
G01Y43294D02*
X842965Y43627D01*
X842585Y43794D01*
X842141Y43877D01*
X841698Y43711D01*
X841318Y43377D01*
X841065Y42877D01*
X840938Y42211D01*
X841065Y41544D01*
X841318Y41044D01*
X841698Y40711D01*
X842141Y40544D01*
X842585Y40627D01*
X842965Y40877D01*
X843218Y41211D01*
G01X847178Y40544D02*
Y45544D01*
G01X855731Y40544D02*
Y45544D01*
X857378Y41377D01*
X859025Y45544D01*
Y40544D01*
G01X863618D02*
Y43877D01*
G01Y43294D02*
X863365Y43627D01*
X862985Y43794D01*
X862541Y43877D01*
X862098Y43711D01*
X861718Y43377D01*
X861465Y42877D01*
X861338Y42211D01*
X861465Y41544D01*
X861718Y41044D01*
X862098Y40711D01*
X862541Y40544D01*
X862985Y40627D01*
X863365Y40877D01*
X863618Y41211D01*
G01X866691Y40544D02*
Y43877D01*
G01Y43211D02*
X867008Y43544D01*
X867325Y43794D01*
X867768Y43877D01*
X868085Y43794D01*
X868465Y43544D01*
G01X871601Y40544D02*
Y45544D01*
G01X873628Y43877D02*
X871601Y41961D01*
G01X872425Y42711D02*
X873755Y40544D01*
G01X881928Y43877D02*
X883828Y40544D01*
G01Y43877D02*
X881928Y40544D01*
G01X891685Y41544D02*
X892065Y40961D01*
X892571Y40627D01*
X893141Y40544D01*
X893648Y40627D01*
X894155Y41044D01*
X894471Y41544D01*
X894535Y42044D01*
X894408Y42627D01*
X893965Y43044D01*
X893521Y43211D01*
X892951D01*
G01X893521D02*
X893901Y43461D01*
X894218Y43877D01*
X894345Y44377D01*
X894218Y44877D01*
X893901Y45294D01*
X893331Y45544D01*
X892761Y45461D01*
X892191Y45127D01*
G01X955841Y-633813D02*
X956136Y-631254D01*
X956579Y-629089D01*
X957169Y-627120D01*
X957908Y-624955D01*
X959089Y-622002D01*
X953183D01*
G01X955841Y1543943D02*
X956136Y1546502D01*
X956579Y1548667D01*
X957169Y1550636D01*
X957908Y1552801D01*
X959089Y1555754D01*
X953183D01*
G01X1175806Y-633813D02*
X1176839Y-633616D01*
X1178020Y-633026D01*
X1178759Y-632042D01*
X1179054Y-630663D01*
X1178759Y-629286D01*
X1177873Y-628104D01*
X1176544Y-627514D01*
X1175068D01*
X1174182Y-627120D01*
X1173444Y-626136D01*
X1173148Y-624758D01*
X1173592Y-623380D01*
X1174625Y-622396D01*
X1175806Y-622002D01*
X1176987Y-622396D01*
X1178020Y-623380D01*
X1178464Y-624758D01*
X1178168Y-626136D01*
X1177430Y-627120D01*
X1176544Y-627514D01*
X1175068D01*
X1173739Y-628104D01*
X1172853Y-629286D01*
X1172558Y-630663D01*
X1172853Y-632042D01*
X1173592Y-633026D01*
X1174773Y-633616D01*
X1175806Y-633813D01*
G01Y1543943D02*
X1176839Y1544140D01*
X1178020Y1544730D01*
X1178759Y1545714D01*
X1179054Y1547093D01*
X1178759Y1548470D01*
X1177873Y1549652D01*
X1176544Y1550242D01*
X1175068D01*
X1174182Y1550636D01*
X1173444Y1551620D01*
X1173148Y1552998D01*
X1173592Y1554376D01*
X1174625Y1555360D01*
X1175806Y1555754D01*
X1176987Y1555360D01*
X1178020Y1554376D01*
X1178464Y1552998D01*
X1178168Y1551620D01*
X1177430Y1550636D01*
X1176544Y1550242D01*
X1175068D01*
X1173739Y1549652D01*
X1172853Y1548470D01*
X1172558Y1547093D01*
X1172853Y1545714D01*
X1173592Y1544730D01*
X1174773Y1544140D01*
X1175806Y1543943D01*
G01X1392965Y-632435D02*
X1393999Y-633419D01*
X1395180Y-633813D01*
X1396361Y-633419D01*
X1397394Y-632239D01*
X1398133Y-630467D01*
X1398428Y-628695D01*
Y-626530D01*
X1398133Y-624758D01*
X1397394Y-623183D01*
X1396508Y-622396D01*
X1395475Y-622002D01*
X1394294Y-622396D01*
X1393408Y-623183D01*
X1392817Y-624364D01*
X1392522Y-625939D01*
X1392817Y-627317D01*
X1393556Y-628695D01*
X1394442Y-629483D01*
X1395475Y-629679D01*
X1396656Y-629286D01*
X1397542Y-628301D01*
X1398428Y-626530D01*
G01X1392965Y1545321D02*
X1393999Y1544337D01*
X1395180Y1543943D01*
X1396361Y1544337D01*
X1397394Y1545517D01*
X1398133Y1547289D01*
X1398428Y1549061D01*
Y1551226D01*
X1398133Y1552998D01*
X1397394Y1554573D01*
X1396508Y1555360D01*
X1395475Y1555754D01*
X1394294Y1555360D01*
X1393408Y1554573D01*
X1392817Y1553392D01*
X1392522Y1551817D01*
X1392817Y1550439D01*
X1393556Y1549061D01*
X1394442Y1548273D01*
X1395475Y1548077D01*
X1396656Y1548470D01*
X1397542Y1549455D01*
X1398428Y1551226D01*
G01X1469736Y309345D02*
X1465637Y299761D01*
X1469484Y298924D01*
X1469736Y309345D01*
G01X1505832Y309766D02*
X1510621Y300508D01*
X1513714Y302944D01*
X1505832Y309766D01*
G01X1473075Y325840D02*
X1476976Y335507D01*
X1473113Y336264D01*
X1473075Y325840D01*
G01X1476879Y661029D02*
X1476235Y650625D01*
X1480140Y651129D01*
X1476879Y661029D01*
G01X1612493Y-633813D02*
Y-622002D01*
X1610721Y-624364D01*
G01Y-633813D02*
X1614264D01*
G01X1624304Y-622002D02*
X1623123Y-622396D01*
X1622237Y-623380D01*
X1621646Y-624561D01*
X1621204Y-626136D01*
X1621056Y-627908D01*
X1621204Y-629679D01*
X1621646Y-631254D01*
X1622237Y-632435D01*
X1623123Y-633419D01*
X1624304Y-633813D01*
X1625485Y-633419D01*
X1626371Y-632435D01*
X1626962Y-631254D01*
X1627404Y-629679D01*
X1627552Y-627908D01*
X1627404Y-626136D01*
X1626962Y-624561D01*
X1626371Y-623380D01*
X1625485Y-622396D01*
X1624304Y-622002D01*
G01X1612493Y1543943D02*
Y1555754D01*
X1610721Y1553392D01*
G01Y1543943D02*
X1614264D01*
G01X1624304Y1555754D02*
X1623123Y1555360D01*
X1622237Y1554376D01*
X1621646Y1553195D01*
X1621204Y1551620D01*
X1621056Y1549848D01*
X1621204Y1548077D01*
X1621646Y1546502D01*
X1622237Y1545321D01*
X1623123Y1544337D01*
X1624304Y1543943D01*
X1625485Y1544337D01*
X1626371Y1545321D01*
X1626962Y1546502D01*
X1627404Y1548077D01*
X1627552Y1549848D01*
X1627404Y1551620D01*
X1626962Y1553195D01*
X1626371Y1554376D01*
X1625485Y1555360D01*
X1624304Y1555754D01*
G01X1653615Y-491631D02*
X1652115Y-490631D01*
X1650365Y-489964D01*
X1648365D01*
X1646115Y-490964D01*
X1644365Y-492631D01*
X1643115Y-494631D01*
X1642115Y-497964D01*
X1641865Y-500964D01*
X1642365Y-503964D01*
X1643115Y-505964D01*
X1644615Y-507964D01*
X1646365Y-509297D01*
X1648115Y-509964D01*
X1649865D01*
X1651615Y-509297D01*
X1653115Y-508298D01*
X1654365Y-506965D01*
G01X1664615Y-509964D02*
Y-496631D01*
G01Y-499297D02*
X1665865Y-497964D01*
X1667115Y-496964D01*
X1668865Y-496631D01*
X1670115Y-496964D01*
X1671615Y-497964D01*
G01X1684365Y-500964D02*
X1692365D01*
X1691615Y-498631D01*
X1690365Y-497298D01*
X1688615Y-496631D01*
X1686865Y-496964D01*
X1685365Y-497964D01*
X1684365Y-500298D01*
X1683865Y-502298D01*
Y-504297D01*
X1684365Y-506298D01*
X1685615Y-508298D01*
X1687115Y-509631D01*
X1688865Y-509964D01*
X1690615Y-509297D01*
X1692365Y-507298D01*
G01X1712615Y-509964D02*
Y-496631D01*
G01Y-498964D02*
X1711615Y-497631D01*
X1710115Y-496964D01*
X1708365Y-496631D01*
X1706615Y-497298D01*
X1705115Y-498631D01*
X1704115Y-500631D01*
X1703615Y-503298D01*
X1704115Y-505964D01*
X1705115Y-507964D01*
X1706615Y-509297D01*
X1708365Y-509964D01*
X1710115Y-509631D01*
X1711615Y-508631D01*
X1712615Y-507298D01*
G01X1728115Y-489964D02*
Y-509964D01*
G01X1724615Y-496631D02*
X1731615D01*
G01X1744365Y-500964D02*
X1752365D01*
X1751615Y-498631D01*
X1750365Y-497298D01*
X1748615Y-496631D01*
X1746865Y-496964D01*
X1745365Y-497964D01*
X1744365Y-500298D01*
X1743865Y-502298D01*
Y-504297D01*
X1744365Y-506298D01*
X1745615Y-508298D01*
X1747115Y-509631D01*
X1748865Y-509964D01*
X1750615Y-509297D01*
X1752365Y-507298D01*
G01X1772615Y-489964D02*
Y-509964D01*
G01Y-506965D02*
X1771615Y-508631D01*
X1770115Y-509631D01*
X1768365Y-509964D01*
X1766365Y-509297D01*
X1764865Y-507631D01*
X1763865Y-505631D01*
X1763615Y-503298D01*
X1763865Y-500964D01*
X1764865Y-498964D01*
X1766365Y-497298D01*
X1768365Y-496631D01*
X1770115Y-496964D01*
X1771365Y-497631D01*
X1772615Y-498964D01*
G01X1639163Y-441056D02*
X1645413Y-461056D01*
X1651663Y-441056D01*
G01X1661663Y-452056D02*
X1669663D01*
X1668913Y-449723D01*
X1667663Y-448390D01*
X1665913Y-447723D01*
X1664163Y-448056D01*
X1662663Y-449056D01*
X1661663Y-451390D01*
X1661163Y-453390D01*
Y-455389D01*
X1661663Y-457390D01*
X1662913Y-459390D01*
X1664413Y-460723D01*
X1666163Y-461056D01*
X1667913Y-460389D01*
X1669663Y-458390D01*
G01X1681913Y-461056D02*
Y-447723D01*
G01Y-450389D02*
X1683163Y-449056D01*
X1684413Y-448056D01*
X1686163Y-447723D01*
X1687413Y-448056D01*
X1688913Y-449056D01*
G01X1701663Y-458723D02*
X1702913Y-460056D01*
X1704663Y-461056D01*
X1706163D01*
X1707663Y-460389D01*
X1708663Y-459390D01*
X1709163Y-458057D01*
X1708913Y-456056D01*
X1707913Y-455056D01*
X1703413Y-453056D01*
X1702413Y-450722D01*
X1702913Y-449056D01*
X1703913Y-448056D01*
X1705413Y-447723D01*
X1706913Y-448056D01*
X1708413Y-449056D01*
G01X1725413Y-447723D02*
Y-461056D01*
G01Y-442390D02*
X1724913Y-442056D01*
Y-441389D01*
X1725413Y-441056D01*
X1725913Y-441389D01*
Y-442056D01*
X1725413Y-442390D01*
G01X1745413Y-461056D02*
X1743913Y-460723D01*
X1742413Y-459390D01*
X1741413Y-457056D01*
X1740913Y-454390D01*
X1741413Y-451723D01*
X1742413Y-449389D01*
X1743913Y-448056D01*
X1745413Y-447723D01*
X1746913Y-448056D01*
X1748413Y-449389D01*
X1749413Y-451723D01*
X1749663Y-454390D01*
X1749413Y-457056D01*
X1748413Y-459390D01*
X1746913Y-460723D01*
X1745413Y-461056D01*
G01X1761163D02*
Y-447723D01*
G01Y-451056D02*
X1762163Y-449389D01*
X1763663Y-448056D01*
X1765663Y-447723D01*
X1767413Y-448056D01*
X1768913Y-449389D01*
X1769663Y-451723D01*
Y-461056D01*
G01X1643115Y-417043D02*
Y-397043D01*
X1649115D01*
X1651115Y-398043D01*
X1652615Y-400376D01*
X1653115Y-403043D01*
X1652615Y-405710D01*
X1651365Y-407710D01*
X1649115Y-408710D01*
X1643115D01*
G01X1673615Y-398710D02*
X1672115Y-397710D01*
X1670365Y-397043D01*
X1668365D01*
X1666115Y-398043D01*
X1664365Y-399710D01*
X1663115Y-401710D01*
X1662115Y-405043D01*
X1661865Y-408043D01*
X1662365Y-411043D01*
X1663115Y-413043D01*
X1664615Y-415043D01*
X1666365Y-416376D01*
X1668115Y-417043D01*
X1669865D01*
X1671615Y-416376D01*
X1673115Y-415377D01*
X1674365Y-414044D01*
G01X1690115Y-406376D02*
X1691115Y-405376D01*
X1691865Y-403710D01*
X1692365Y-401376D01*
X1691865Y-399376D01*
X1690865Y-398043D01*
X1689115Y-397043D01*
X1682365D01*
Y-417043D01*
X1690615D01*
X1692365Y-415710D01*
X1693365Y-413710D01*
X1693865Y-411376D01*
X1693365Y-409043D01*
X1691865Y-407043D01*
X1690115Y-406376D01*
X1682365D01*
G01X1722365Y-417043D02*
Y-397043D01*
X1733865Y-417043D01*
Y-397043D01*
G01X1748115Y-417043D02*
X1746615Y-416710D01*
X1745115Y-415377D01*
X1744115Y-413043D01*
X1743615Y-410377D01*
X1744115Y-407710D01*
X1745115Y-405376D01*
X1746615Y-404043D01*
X1748115Y-403710D01*
X1749615Y-404043D01*
X1751115Y-405376D01*
X1752115Y-407710D01*
X1752365Y-410377D01*
X1752115Y-413043D01*
X1751115Y-415377D01*
X1749615Y-416710D01*
X1748115Y-417043D01*
G01X1768115Y-417710D02*
X1767615Y-417376D01*
Y-416710D01*
X1768115Y-416376D01*
X1768615Y-416710D01*
Y-417376D01*
X1768115Y-417710D01*
G01X1651559Y-372830D02*
Y-347830D01*
X1659749Y-368663D01*
X1667939Y-347830D01*
Y-372830D01*
G01X1684949D02*
X1683059Y-372413D01*
X1681169Y-370747D01*
X1679909Y-367830D01*
X1679279Y-364497D01*
X1679909Y-361164D01*
X1681169Y-358247D01*
X1683059Y-356580D01*
X1684949Y-356164D01*
X1686839Y-356580D01*
X1688729Y-358247D01*
X1689989Y-361164D01*
X1690304Y-364497D01*
X1689989Y-367830D01*
X1688729Y-370747D01*
X1686839Y-372413D01*
X1684949Y-372830D01*
G01X1715819Y-347830D02*
Y-372830D01*
G01Y-369081D02*
X1714559Y-371164D01*
X1712669Y-372413D01*
X1710464Y-372830D01*
X1707944Y-371997D01*
X1706054Y-369914D01*
X1704794Y-367414D01*
X1704479Y-364497D01*
X1704794Y-361580D01*
X1706054Y-359080D01*
X1707944Y-356997D01*
X1710464Y-356164D01*
X1712669Y-356580D01*
X1714244Y-357414D01*
X1715819Y-359080D01*
G01X1730624Y-361580D02*
X1740704D01*
X1739759Y-358663D01*
X1738184Y-356997D01*
X1735979Y-356164D01*
X1733774Y-356580D01*
X1731884Y-357830D01*
X1730624Y-360747D01*
X1729994Y-363247D01*
Y-365747D01*
X1730624Y-368247D01*
X1732199Y-370747D01*
X1734089Y-372413D01*
X1736294Y-372830D01*
X1738499Y-371997D01*
X1740704Y-369497D01*
G01X1760549Y-372830D02*
Y-347830D01*
G01X1832920Y-633813D02*
Y-622002D01*
X1831148Y-624364D01*
G01Y-633813D02*
X1834691D01*
G01X1844731D02*
Y-622002D01*
X1842959Y-624364D01*
G01Y-633813D02*
X1846502D01*
G01X1821293Y-541499D02*
X1825703Y-566499D01*
X1830743Y-541499D01*
X1835783Y-566499D01*
X1840193Y-541499D01*
G01X1855943Y-549833D02*
Y-566499D01*
G01Y-543166D02*
X1855313Y-542749D01*
Y-541916D01*
X1855943Y-541499D01*
X1856573Y-541916D01*
Y-542749D01*
X1855943Y-543166D01*
G01X1876418Y-563583D02*
X1877993Y-565249D01*
X1880198Y-566499D01*
X1882088D01*
X1883978Y-565666D01*
X1885238Y-564416D01*
X1885868Y-562750D01*
X1885553Y-560249D01*
X1884293Y-558999D01*
X1878623Y-556500D01*
X1877363Y-553582D01*
X1877993Y-551499D01*
X1879253Y-550249D01*
X1881143Y-549833D01*
X1883033Y-550249D01*
X1884923Y-551499D01*
G01X1906343Y-541499D02*
Y-566499D01*
G01X1901933Y-549833D02*
X1910753D01*
G01X1927133Y-566499D02*
Y-549833D01*
G01Y-553165D02*
X1928708Y-551499D01*
X1930283Y-550249D01*
X1932488Y-549833D01*
X1934063Y-550249D01*
X1935953Y-551499D01*
G01X1956743Y-566499D02*
X1954853Y-566082D01*
X1952963Y-564416D01*
X1951703Y-561499D01*
X1951073Y-558166D01*
X1951703Y-554833D01*
X1952963Y-551916D01*
X1954853Y-550249D01*
X1956743Y-549833D01*
X1958633Y-550249D01*
X1960523Y-551916D01*
X1961783Y-554833D01*
X1962098Y-558166D01*
X1961783Y-561499D01*
X1960523Y-564416D01*
X1958633Y-566082D01*
X1956743Y-566499D01*
G01X1976588D02*
Y-549833D01*
G01Y-553999D02*
X1977848Y-551916D01*
X1979738Y-550249D01*
X1982258Y-549833D01*
X1984463Y-550249D01*
X1986353Y-551916D01*
X1987298Y-554833D01*
Y-566499D01*
G01X2039273Y-543583D02*
X2037383Y-542332D01*
X2035178Y-541499D01*
X2032658D01*
X2029823Y-542749D01*
X2027618Y-544832D01*
X2026043Y-547333D01*
X2024783Y-551499D01*
X2024468Y-555249D01*
X2025098Y-558999D01*
X2026043Y-561499D01*
X2027933Y-564000D01*
X2030138Y-565666D01*
X2032343Y-566499D01*
X2034548D01*
X2036753Y-565666D01*
X2038643Y-564416D01*
X2040218Y-562750D01*
G01X2057543Y-566499D02*
X2055653Y-566082D01*
X2053763Y-564416D01*
X2052503Y-561499D01*
X2051873Y-558166D01*
X2052503Y-554833D01*
X2053763Y-551916D01*
X2055653Y-550249D01*
X2057543Y-549833D01*
X2059433Y-550249D01*
X2061323Y-551916D01*
X2062583Y-554833D01*
X2062898Y-558166D01*
X2062583Y-561499D01*
X2061323Y-564416D01*
X2059433Y-566082D01*
X2057543Y-566499D01*
G01X2078333D02*
Y-549833D01*
G01Y-553165D02*
X2079908Y-551499D01*
X2081483Y-550249D01*
X2083688Y-549833D01*
X2085263Y-550249D01*
X2087153Y-551499D01*
G01X2102273Y-574832D02*
Y-549833D01*
G01Y-553582D02*
X2103848Y-551499D01*
X2105423Y-550249D01*
X2107943Y-549833D01*
X2110148Y-550249D01*
X2112353Y-552332D01*
X2113298Y-555249D01*
X2113613Y-558166D01*
X2113298Y-561083D01*
X2112353Y-564000D01*
X2110463Y-565666D01*
X2107943Y-566499D01*
X2105738Y-566082D01*
X2103533Y-564833D01*
X2102273Y-563166D01*
G01X2133143Y-566499D02*
X2131253Y-566082D01*
X2129363Y-564416D01*
X2128103Y-561499D01*
X2127473Y-558166D01*
X2128103Y-554833D01*
X2129363Y-551916D01*
X2131253Y-550249D01*
X2133143Y-549833D01*
X2135033Y-550249D01*
X2136923Y-551916D01*
X2138183Y-554833D01*
X2138498Y-558166D01*
X2138183Y-561499D01*
X2136923Y-564416D01*
X2135033Y-566082D01*
X2133143Y-566499D01*
G01X2153933D02*
Y-549833D01*
G01Y-553165D02*
X2155508Y-551499D01*
X2157083Y-550249D01*
X2159288Y-549833D01*
X2160863Y-550249D01*
X2162753Y-551499D01*
G01X2189213Y-566499D02*
Y-549833D01*
G01Y-552749D02*
X2187953Y-551083D01*
X2186063Y-550249D01*
X2183858Y-549833D01*
X2181653Y-550666D01*
X2179763Y-552332D01*
X2178503Y-554833D01*
X2177873Y-558166D01*
X2178503Y-561499D01*
X2179763Y-564000D01*
X2181653Y-565666D01*
X2183858Y-566499D01*
X2186063Y-566082D01*
X2187953Y-564833D01*
X2189213Y-563166D01*
G01X2208743Y-541499D02*
Y-566499D01*
G01X2204333Y-549833D02*
X2213153D01*
G01X2233943D02*
Y-566499D01*
G01Y-543166D02*
X2233313Y-542749D01*
Y-541916D01*
X2233943Y-541499D01*
X2234573Y-541916D01*
Y-542749D01*
X2233943Y-543166D01*
G01X2259143Y-566499D02*
X2257253Y-566082D01*
X2255363Y-564416D01*
X2254103Y-561499D01*
X2253473Y-558166D01*
X2254103Y-554833D01*
X2255363Y-551916D01*
X2257253Y-550249D01*
X2259143Y-549833D01*
X2261033Y-550249D01*
X2262923Y-551916D01*
X2264183Y-554833D01*
X2264498Y-558166D01*
X2264183Y-561499D01*
X2262923Y-564416D01*
X2261033Y-566082D01*
X2259143Y-566499D01*
G01X2278988D02*
Y-549833D01*
G01Y-553999D02*
X2280248Y-551916D01*
X2282138Y-550249D01*
X2284658Y-549833D01*
X2286863Y-550249D01*
X2288753Y-551916D01*
X2289698Y-554833D01*
Y-566499D01*
G01X1844319Y-487989D02*
X1850569Y-507989D01*
X1856819Y-487989D01*
G01X1870569Y-494656D02*
Y-507989D01*
G01Y-489323D02*
X1870069Y-488989D01*
Y-488322D01*
X1870569Y-487989D01*
X1871069Y-488322D01*
Y-488989D01*
X1870569Y-489323D01*
G01X1890569Y-507989D02*
Y-487989D01*
G01X1906819Y-498989D02*
X1914819D01*
X1914069Y-496656D01*
X1912819Y-495323D01*
X1911069Y-494656D01*
X1909319Y-494989D01*
X1907819Y-495989D01*
X1906819Y-498323D01*
X1906319Y-500323D01*
Y-502322D01*
X1906819Y-504323D01*
X1908069Y-506323D01*
X1909569Y-507656D01*
X1911319Y-507989D01*
X1913069Y-507322D01*
X1914819Y-505323D01*
G01X1935069Y-507989D02*
Y-494656D01*
G01Y-496989D02*
X1934069Y-495656D01*
X1932569Y-494989D01*
X1930819Y-494656D01*
X1929069Y-495323D01*
X1927569Y-496656D01*
X1926569Y-498656D01*
X1926069Y-501323D01*
X1926569Y-503989D01*
X1927569Y-505989D01*
X1929069Y-507322D01*
X1930819Y-507989D01*
X1932569Y-507656D01*
X1934069Y-506656D01*
X1935069Y-505323D01*
G01X1946319Y-507989D02*
Y-494656D01*
G01Y-497989D02*
X1947319Y-496322D01*
X1948819Y-494989D01*
X1950819Y-494656D01*
X1952569Y-494989D01*
X1954069Y-496322D01*
X1954819Y-498656D01*
Y-507989D01*
G01X1985569Y-487989D02*
Y-507989D01*
X1995569D01*
G01X2010569Y-494656D02*
Y-507989D01*
G01Y-489323D02*
X2010069Y-488989D01*
Y-488322D01*
X2010569Y-487989D01*
X2011069Y-488322D01*
Y-488989D01*
X2010569Y-489323D01*
G01X1856316Y-415068D02*
Y-395068D01*
X1853316Y-399068D01*
G01Y-415068D02*
X1859316D01*
G01X1871566Y-406735D02*
X1873316Y-404401D01*
X1874816Y-403068D01*
X1876816Y-402402D01*
X1878566Y-403068D01*
X1879816Y-404401D01*
X1880816Y-406401D01*
X1881066Y-408735D01*
X1880816Y-410735D01*
X1879816Y-412735D01*
X1878316Y-414401D01*
X1876566Y-415068D01*
X1874566Y-414401D01*
X1872816Y-412402D01*
X1871816Y-409401D01*
X1871566Y-406068D01*
X1872066Y-401735D01*
X1872816Y-399401D01*
X1874066Y-397068D01*
X1875816Y-395401D01*
X1877566Y-395068D01*
X1879316Y-395735D01*
X1880566Y-397401D01*
G01X1890816Y-411068D02*
X1892316Y-413402D01*
X1894316Y-414735D01*
X1896566Y-415068D01*
X1898566Y-414735D01*
X1900566Y-413068D01*
X1901816Y-411068D01*
X1902066Y-409068D01*
X1901566Y-406735D01*
X1899816Y-405068D01*
X1898066Y-404401D01*
X1895816D01*
G01X1898066D02*
X1899566Y-403401D01*
X1900816Y-401735D01*
X1901316Y-399735D01*
X1900816Y-397735D01*
X1899566Y-396068D01*
X1897316Y-395068D01*
X1895066Y-395401D01*
X1892816Y-396735D01*
G01X1919316Y-415068D02*
Y-395068D01*
X1910066Y-409401D01*
X1922566D01*
G01X1935816Y-415068D02*
X1936316Y-410735D01*
X1937066Y-407068D01*
X1938066Y-403735D01*
X1939316Y-400068D01*
X1941316Y-395068D01*
X1931316D01*
G01X1848635Y-355789D02*
X1849895Y-354540D01*
X1850840Y-352457D01*
X1851470Y-349539D01*
X1850840Y-347040D01*
X1849580Y-345373D01*
X1847375Y-344123D01*
X1838870D01*
Y-369123D01*
X1849265D01*
X1851470Y-367457D01*
X1852730Y-364956D01*
X1853360Y-362040D01*
X1852730Y-359124D01*
X1850840Y-356623D01*
X1848635Y-355789D01*
X1838870D01*
G01X1866905Y-369123D02*
Y-352457D01*
G01Y-355789D02*
X1868480Y-354123D01*
X1870055Y-352873D01*
X1872260Y-352457D01*
X1873835Y-352873D01*
X1875725Y-354123D01*
G01X1889900Y-376623D02*
X1891790Y-377456D01*
X1894310Y-376623D01*
X1895885Y-374957D01*
X1897145Y-372873D01*
X1899035Y-366207D01*
X1903130Y-352457D01*
G01X1893050D02*
X1899035Y-366207D01*
G01X1926755Y-354540D02*
X1924550Y-352873D01*
X1922660Y-352457D01*
X1920140Y-353290D01*
X1918250Y-354956D01*
X1916990Y-357873D01*
X1916675Y-360790D01*
X1916990Y-363707D01*
X1918250Y-366207D01*
X1920140Y-368290D01*
X1922660Y-369123D01*
X1924865Y-368290D01*
X1926755Y-366624D01*
G01X1942190Y-357873D02*
X1952270D01*
X1951325Y-354956D01*
X1949750Y-353290D01*
X1947545Y-352457D01*
X1945340Y-352873D01*
X1943450Y-354123D01*
X1942190Y-357040D01*
X1941560Y-359540D01*
Y-362040D01*
X1942190Y-364540D01*
X1943765Y-367040D01*
X1945655Y-368706D01*
X1947860Y-369123D01*
X1950065Y-368290D01*
X1952270Y-365790D01*
G01X2004245Y-346207D02*
X2002355Y-344956D01*
X2000150Y-344123D01*
X1997630D01*
X1994795Y-345373D01*
X1992590Y-347456D01*
X1991015Y-349957D01*
X1989755Y-354123D01*
X1989440Y-357873D01*
X1990070Y-361623D01*
X1991015Y-364123D01*
X1992905Y-366624D01*
X1995110Y-368290D01*
X1997315Y-369123D01*
X1999520D01*
X2001725Y-368290D01*
X2003615Y-367040D01*
X2005190Y-365374D01*
G01X2028185Y-369123D02*
Y-352457D01*
G01Y-355373D02*
X2026925Y-353707D01*
X2025035Y-352873D01*
X2022830Y-352457D01*
X2020625Y-353290D01*
X2018735Y-354956D01*
X2017475Y-357457D01*
X2016845Y-360790D01*
X2017475Y-364123D01*
X2018735Y-366624D01*
X2020625Y-368290D01*
X2022830Y-369123D01*
X2025035Y-368706D01*
X2026925Y-367457D01*
X2028185Y-365790D01*
G01X2042360Y-369123D02*
Y-352457D01*
G01Y-356623D02*
X2043620Y-354540D01*
X2045510Y-352873D01*
X2048030Y-352457D01*
X2050235Y-352873D01*
X2052125Y-354540D01*
X2053070Y-357457D01*
Y-369123D01*
G01X2066300Y-376623D02*
X2068190Y-377456D01*
X2070710Y-376623D01*
X2072285Y-374957D01*
X2073545Y-372873D01*
X2075435Y-366207D01*
X2079530Y-352457D01*
G01X2069450D02*
X2075435Y-366207D01*
G01X2098115Y-369123D02*
X2096225Y-368706D01*
X2094335Y-367040D01*
X2093075Y-364123D01*
X2092445Y-360790D01*
X2093075Y-357457D01*
X2094335Y-354540D01*
X2096225Y-352873D01*
X2098115Y-352457D01*
X2100005Y-352873D01*
X2101895Y-354540D01*
X2103155Y-357457D01*
X2103470Y-360790D01*
X2103155Y-364123D01*
X2101895Y-367040D01*
X2100005Y-368706D01*
X2098115Y-369123D01*
G01X2117960D02*
Y-352457D01*
G01Y-356623D02*
X2119220Y-354540D01*
X2121110Y-352873D01*
X2123630Y-352457D01*
X2125835Y-352873D01*
X2127725Y-354540D01*
X2128670Y-357457D01*
Y-369123D01*
G01X2167415Y-344123D02*
Y-369123D01*
X2180015D01*
G01X2205215D02*
X2192615D01*
Y-344123D01*
X2205215D01*
G01X2200175Y-356206D02*
X2192615D01*
G01X2217185Y-369123D02*
Y-344123D01*
X2223485D01*
X2226005Y-345373D01*
X2227895Y-347040D01*
X2229470Y-349539D01*
X2230730Y-352457D01*
X2231045Y-356623D01*
X2230730Y-360790D01*
X2229470Y-363707D01*
X2227895Y-366207D01*
X2226005Y-367873D01*
X2223485Y-369123D01*
X2217185D01*
G01X2277035Y-355789D02*
X2278295Y-354540D01*
X2279240Y-352457D01*
X2279870Y-349539D01*
X2279240Y-347040D01*
X2277980Y-345373D01*
X2275775Y-344123D01*
X2267270D01*
Y-369123D01*
X2277665D01*
X2279870Y-367457D01*
X2281130Y-364956D01*
X2281760Y-362040D01*
X2281130Y-359124D01*
X2279240Y-356623D01*
X2277035Y-355789D01*
X2267270D01*
G01X2299715Y-369123D02*
X2297825Y-368706D01*
X2295935Y-367040D01*
X2294675Y-364123D01*
X2294045Y-360790D01*
X2294675Y-357457D01*
X2295935Y-354540D01*
X2297825Y-352873D01*
X2299715Y-352457D01*
X2301605Y-352873D01*
X2303495Y-354540D01*
X2304755Y-357457D01*
X2305070Y-360790D01*
X2304755Y-364123D01*
X2303495Y-367040D01*
X2301605Y-368706D01*
X2299715Y-369123D01*
G01X2330585D02*
Y-352457D01*
G01Y-355373D02*
X2329325Y-353707D01*
X2327435Y-352873D01*
X2325230Y-352457D01*
X2323025Y-353290D01*
X2321135Y-354956D01*
X2319875Y-357457D01*
X2319245Y-360790D01*
X2319875Y-364123D01*
X2321135Y-366624D01*
X2323025Y-368290D01*
X2325230Y-369123D01*
X2327435Y-368706D01*
X2329325Y-367457D01*
X2330585Y-365790D01*
G01X2345705Y-369123D02*
Y-352457D01*
G01Y-355789D02*
X2347280Y-354123D01*
X2348855Y-352873D01*
X2351060Y-352457D01*
X2352635Y-352873D01*
X2354525Y-354123D01*
G01X2380985Y-344123D02*
Y-369123D01*
G01Y-365374D02*
X2379725Y-367457D01*
X2377835Y-368706D01*
X2375630Y-369123D01*
X2373110Y-368290D01*
X2371220Y-366207D01*
X2369960Y-363707D01*
X2369645Y-360790D01*
X2369960Y-357873D01*
X2371220Y-355373D01*
X2373110Y-353290D01*
X2375630Y-352457D01*
X2377835Y-352873D01*
X2379410Y-353707D01*
X2380985Y-355373D01*
G01X1832920Y1543943D02*
Y1555754D01*
X1831148Y1553392D01*
G01Y1543943D02*
X1834691D01*
G01X1844731D02*
Y1555754D01*
X1842959Y1553392D01*
G01Y1543943D02*
X1846502D01*
G01X1865096Y-463284D02*
X1867096Y-464950D01*
X1869346Y-465950D01*
X1871346D01*
X1873346Y-464950D01*
X1874846Y-463284D01*
X1875596Y-460950D01*
X1875096Y-458617D01*
X1873846Y-456617D01*
X1871596Y-455283D01*
X1868596Y-454617D01*
X1866846Y-453284D01*
X1866096Y-450950D01*
X1866596Y-448617D01*
X1867846Y-446950D01*
X1869596Y-445950D01*
X1871346D01*
X1873096Y-446617D01*
X1874596Y-448283D01*
G01X1895846Y-447617D02*
X1894346Y-446617D01*
X1892596Y-445950D01*
X1890596D01*
X1888346Y-446950D01*
X1886596Y-448617D01*
X1885346Y-450617D01*
X1884346Y-453950D01*
X1884096Y-456950D01*
X1884596Y-459950D01*
X1885346Y-461950D01*
X1886846Y-463950D01*
X1888596Y-465283D01*
X1890346Y-465950D01*
X1892096D01*
X1893846Y-465283D01*
X1895346Y-464284D01*
X1896596Y-462951D01*
G01X2050695Y-633813D02*
Y-622002D01*
X2048923Y-624364D01*
G01Y-633813D02*
X2052466D01*
G01X2059701Y-623970D02*
X2060587Y-622790D01*
X2061620Y-622199D01*
X2062801Y-622002D01*
X2064278Y-622396D01*
X2065311Y-623380D01*
X2065606Y-624561D01*
X2065459Y-625742D01*
X2064868Y-626726D01*
X2061915Y-628695D01*
X2060587Y-630073D01*
X2059701Y-632042D01*
X2059406Y-633813D01*
X2065606D01*
G01X2050695Y1543943D02*
Y1555754D01*
X2048923Y1553392D01*
G01Y1543943D02*
X2052466D01*
G01X2059701Y1553786D02*
X2060587Y1554966D01*
X2061620Y1555557D01*
X2062801Y1555754D01*
X2064278Y1555360D01*
X2065311Y1554376D01*
X2065606Y1553195D01*
X2065459Y1552014D01*
X2064868Y1551030D01*
X2061915Y1549061D01*
X2060587Y1547683D01*
X2059701Y1545714D01*
X2059406Y1543943D01*
X2065606D01*
G01X2138950Y309970D02*
X2144248Y300992D01*
X2147200Y303598D01*
X2138950Y309970D01*
G01X2161246Y-443171D02*
Y-463171D01*
G01X2155496Y-443171D02*
X2166996D01*
G01X2176996Y-463171D02*
Y-443171D01*
G01Y-452837D02*
X2178246Y-451171D01*
X2179496Y-450171D01*
X2181496Y-449838D01*
X2182996Y-450171D01*
X2184746Y-451504D01*
X2185496Y-453505D01*
Y-463171D01*
G01X2201246Y-449838D02*
Y-463171D01*
G01Y-444505D02*
X2200746Y-444171D01*
Y-443504D01*
X2201246Y-443171D01*
X2201746Y-443504D01*
Y-444171D01*
X2201246Y-444505D01*
G01X2225246Y-451504D02*
X2223496Y-450171D01*
X2221996Y-449838D01*
X2219996Y-450505D01*
X2218496Y-451838D01*
X2217496Y-454171D01*
X2217246Y-456505D01*
X2217496Y-458838D01*
X2218496Y-460838D01*
X2219996Y-462504D01*
X2221996Y-463171D01*
X2223746Y-462504D01*
X2225246Y-461171D01*
G01X2236996Y-463171D02*
Y-443171D01*
G01X2244996Y-449838D02*
X2236996Y-457504D01*
G01X2240246Y-454504D02*
X2245496Y-463171D01*
G01X2256996D02*
Y-449838D01*
G01Y-453171D02*
X2257996Y-451504D01*
X2259496Y-450171D01*
X2261496Y-449838D01*
X2263246Y-450171D01*
X2264746Y-451504D01*
X2265496Y-453838D01*
Y-463171D01*
G01X2277496Y-454171D02*
X2285496D01*
X2284746Y-451838D01*
X2283496Y-450505D01*
X2281746Y-449838D01*
X2279996Y-450171D01*
X2278496Y-451171D01*
X2277496Y-453505D01*
X2276996Y-455505D01*
Y-457504D01*
X2277496Y-459505D01*
X2278746Y-461505D01*
X2280246Y-462838D01*
X2281996Y-463171D01*
X2283746Y-462504D01*
X2285496Y-460505D01*
G01X2297496Y-460838D02*
X2298746Y-462171D01*
X2300496Y-463171D01*
X2301996D01*
X2303496Y-462504D01*
X2304496Y-461505D01*
X2304996Y-460172D01*
X2304746Y-458171D01*
X2303746Y-457171D01*
X2299246Y-455171D01*
X2298246Y-452837D01*
X2298746Y-451171D01*
X2299746Y-450171D01*
X2301246Y-449838D01*
X2302746Y-450171D01*
X2304246Y-451171D01*
G01X2317496Y-460838D02*
X2318746Y-462171D01*
X2320496Y-463171D01*
X2321996D01*
X2323496Y-462504D01*
X2324496Y-461505D01*
X2324996Y-460172D01*
X2324746Y-458171D01*
X2323746Y-457171D01*
X2319246Y-455171D01*
X2318246Y-452837D01*
X2318746Y-451171D01*
X2319746Y-450171D01*
X2321246Y-449838D01*
X2322746Y-450171D01*
X2324246Y-451171D01*
G01X2205852Y-509964D02*
Y-489964D01*
X2210852D01*
X2212852Y-490964D01*
X2214352Y-492297D01*
X2215602Y-494297D01*
X2216602Y-496631D01*
X2216852Y-499964D01*
X2216602Y-503298D01*
X2215602Y-505631D01*
X2214352Y-507631D01*
X2212852Y-508964D01*
X2210852Y-509964D01*
X2205852D01*
G01X2235852D02*
Y-496631D01*
G01Y-498964D02*
X2234852Y-497631D01*
X2233352Y-496964D01*
X2231602Y-496631D01*
X2229852Y-497298D01*
X2228352Y-498631D01*
X2227352Y-500631D01*
X2226852Y-503298D01*
X2227352Y-505964D01*
X2228352Y-507964D01*
X2229852Y-509297D01*
X2231602Y-509964D01*
X2233352Y-509631D01*
X2234852Y-508631D01*
X2235852Y-507298D01*
G01X2251352Y-489964D02*
Y-509964D01*
G01X2247852Y-496631D02*
X2254852D01*
G01X2267602Y-500964D02*
X2275602D01*
X2274852Y-498631D01*
X2273602Y-497298D01*
X2271852Y-496631D01*
X2270102Y-496964D01*
X2268602Y-497964D01*
X2267602Y-500298D01*
X2267102Y-502298D01*
Y-504297D01*
X2267602Y-506298D01*
X2268852Y-508298D01*
X2270352Y-509631D01*
X2272102Y-509964D01*
X2273852Y-509297D01*
X2275602Y-507298D01*
G01X2270365Y-633813D02*
Y-622002D01*
X2268593Y-624364D01*
G01Y-633813D02*
X2272136D01*
G01X2278928Y-631451D02*
X2279814Y-632829D01*
X2280995Y-633616D01*
X2282324Y-633813D01*
X2283505Y-633616D01*
X2284686Y-632632D01*
X2285424Y-631451D01*
X2285572Y-630270D01*
X2285276Y-628892D01*
X2284243Y-627908D01*
X2283209Y-627514D01*
X2281881D01*
G01X2283209D02*
X2284095Y-626923D01*
X2284834Y-625939D01*
X2285129Y-624758D01*
X2284834Y-623577D01*
X2284095Y-622593D01*
X2282767Y-622002D01*
X2281438Y-622199D01*
X2280109Y-622986D01*
G01X2270365Y1543943D02*
Y1555754D01*
X2268593Y1553392D01*
G01Y1543943D02*
X2272136D01*
G01X2278928Y1546305D02*
X2279814Y1544927D01*
X2280995Y1544140D01*
X2282324Y1543943D01*
X2283505Y1544140D01*
X2284686Y1545124D01*
X2285424Y1546305D01*
X2285572Y1547486D01*
X2285276Y1548864D01*
X2284243Y1549848D01*
X2283209Y1550242D01*
X2281881D01*
G01X2283209D02*
X2284095Y1550833D01*
X2284834Y1551817D01*
X2285129Y1552998D01*
X2284834Y1554179D01*
X2284095Y1555163D01*
X2282767Y1555754D01*
X2281438Y1555557D01*
X2280109Y1554770D01*
G01X2350857Y-492170D02*
X2352357Y-490171D01*
X2354107Y-489170D01*
X2356107Y-488837D01*
X2358607Y-489504D01*
X2360357Y-491170D01*
X2360857Y-493170D01*
X2360607Y-495171D01*
X2359607Y-496837D01*
X2354607Y-500170D01*
X2352357Y-502504D01*
X2350857Y-505838D01*
X2350357Y-508837D01*
X2360857D01*
G01X2375607Y-488837D02*
X2373607Y-489504D01*
X2372107Y-491170D01*
X2371107Y-493170D01*
X2370357Y-495837D01*
X2370107Y-498837D01*
X2370357Y-501837D01*
X2371107Y-504504D01*
X2372107Y-506504D01*
X2373607Y-508170D01*
X2375607Y-508837D01*
X2377607Y-508170D01*
X2379107Y-506504D01*
X2380107Y-504504D01*
X2380857Y-501837D01*
X2381107Y-498837D01*
X2380857Y-495837D01*
X2380107Y-493170D01*
X2379107Y-491170D01*
X2377607Y-489504D01*
X2375607Y-488837D01*
G01X2395607Y-508837D02*
Y-488837D01*
X2392607Y-492837D01*
G01Y-508837D02*
X2398607D01*
G01X2415107D02*
X2415607Y-504504D01*
X2416357Y-500837D01*
X2417357Y-497504D01*
X2418607Y-493837D01*
X2420607Y-488837D01*
X2410607D01*
G01X2432357Y-502171D02*
X2438857D01*
G01X2455607Y-488837D02*
X2453607Y-489504D01*
X2452107Y-491170D01*
X2451107Y-493170D01*
X2450357Y-495837D01*
X2450107Y-498837D01*
X2450357Y-501837D01*
X2451107Y-504504D01*
X2452107Y-506504D01*
X2453607Y-508170D01*
X2455607Y-508837D01*
X2457607Y-508170D01*
X2459107Y-506504D01*
X2460107Y-504504D01*
X2460857Y-501837D01*
X2461107Y-498837D01*
X2460857Y-495837D01*
X2460107Y-493170D01*
X2459107Y-491170D01*
X2457607Y-489504D01*
X2455607Y-488837D01*
G01X2470857Y-492170D02*
X2472357Y-490171D01*
X2474107Y-489170D01*
X2476107Y-488837D01*
X2478607Y-489504D01*
X2480357Y-491170D01*
X2480857Y-493170D01*
X2480607Y-495171D01*
X2479607Y-496837D01*
X2474607Y-500170D01*
X2472357Y-502504D01*
X2470857Y-505838D01*
X2470357Y-508837D01*
X2480857D01*
G01X2492357Y-502171D02*
X2498857D01*
G01X2510857Y-492170D02*
X2512357Y-490171D01*
X2514107Y-489170D01*
X2516107Y-488837D01*
X2518607Y-489504D01*
X2520357Y-491170D01*
X2520857Y-493170D01*
X2520607Y-495171D01*
X2519607Y-496837D01*
X2514607Y-500170D01*
X2512357Y-502504D01*
X2510857Y-505838D01*
X2510357Y-508837D01*
X2520857D01*
G01X2535607D02*
X2537357Y-508504D01*
X2539357Y-507504D01*
X2540607Y-505838D01*
X2541107Y-503504D01*
X2540607Y-501171D01*
X2539107Y-499171D01*
X2536857Y-498170D01*
X2534357D01*
X2532857Y-497504D01*
X2531607Y-495837D01*
X2531107Y-493504D01*
X2531857Y-491170D01*
X2533607Y-489504D01*
X2535607Y-488837D01*
X2537607Y-489504D01*
X2539357Y-491170D01*
X2540107Y-493504D01*
X2539607Y-495837D01*
X2538357Y-497504D01*
X2536857Y-498170D01*
X2534357D01*
X2532107Y-499171D01*
X2530607Y-501171D01*
X2530107Y-503504D01*
X2530607Y-505838D01*
X2531857Y-507504D01*
X2533857Y-508504D01*
X2535607Y-508837D01*
G01X2386664Y-459281D02*
Y-439281D01*
X2383664Y-443281D01*
G01Y-459281D02*
X2389664D01*
G01X2406664Y-459948D02*
X2406164Y-459614D01*
Y-458948D01*
X2406664Y-458614D01*
X2407164Y-458948D01*
Y-459614D01*
X2406664Y-459948D01*
G01X2426664Y-439281D02*
X2424664Y-439948D01*
X2423164Y-441614D01*
X2422164Y-443614D01*
X2421414Y-446281D01*
X2421164Y-449281D01*
X2421414Y-452281D01*
X2422164Y-454948D01*
X2423164Y-456948D01*
X2424664Y-458614D01*
X2426664Y-459281D01*
X2428664Y-458614D01*
X2430164Y-456948D01*
X2431164Y-454948D01*
X2431914Y-452281D01*
X2432164Y-449281D01*
X2431914Y-446281D01*
X2431164Y-443614D01*
X2430164Y-441614D01*
X2428664Y-439948D01*
X2426664Y-439281D01*
G01X2439164Y-459281D02*
Y-445948D01*
G01Y-449615D02*
X2439914Y-447948D01*
X2441164Y-446615D01*
X2442914Y-445948D01*
X2444664Y-446615D01*
X2445914Y-447948D01*
X2446664Y-449615D01*
Y-459281D01*
G01Y-449615D02*
X2447414Y-447948D01*
X2448664Y-446615D01*
X2450414Y-445948D01*
X2452164Y-446615D01*
X2453414Y-447948D01*
X2454164Y-449948D01*
Y-459281D01*
G01X2459164D02*
Y-445948D01*
G01Y-449615D02*
X2459914Y-447948D01*
X2461164Y-446615D01*
X2462914Y-445948D01*
X2464664Y-446615D01*
X2465914Y-447948D01*
X2466664Y-449615D01*
Y-459281D01*
G01Y-449615D02*
X2467414Y-447948D01*
X2468664Y-446615D01*
X2470414Y-445948D01*
X2472164Y-446615D01*
X2473414Y-447948D01*
X2474164Y-449948D01*
Y-459281D01*
G01X2490034Y-633813D02*
Y-622002D01*
X2488262Y-624364D01*
G01Y-633813D02*
X2491805D01*
G01X2503617D02*
Y-622002D01*
X2498154Y-630467D01*
X2505536D01*
G01X2490034Y1543943D02*
Y1555754D01*
X2488262Y1553392D01*
G01Y1543943D02*
X2491805D01*
G01X2503617D02*
Y1555754D01*
X2498154Y1547289D01*
X2505536D01*
G01X2615663Y-514041D02*
X2616402Y-515222D01*
X2617287Y-516009D01*
X2618321Y-516403D01*
X2619502Y-516009D01*
X2620388Y-515222D01*
X2621274Y-514041D01*
X2621569Y-512466D01*
Y-504592D01*
G01X2616844Y-288710D02*
X2620387D01*
G01X2618616D02*
Y-300521D01*
G01X2616844D02*
X2620387D01*
G01X2615516Y-84829D02*
Y-73018D01*
G01X2621716D02*
Y-84829D01*
G01Y-78924D02*
X2615516D01*
G01X2619502Y136958D02*
X2622455D01*
Y133415D01*
X2621569Y132234D01*
X2620535Y131447D01*
X2619059Y131053D01*
X2617583Y131447D01*
X2616549Y132234D01*
X2615663Y133415D01*
X2615073Y134793D01*
X2614777Y136368D01*
Y137746D01*
X2615073Y138927D01*
X2615663Y140305D01*
X2616549Y141486D01*
X2617435Y142273D01*
X2618616Y142864D01*
X2619649D01*
X2620830Y142470D01*
X2621716Y141683D01*
G01X2615432Y347125D02*
Y358936D01*
X2621042D01*
G01X2618975Y353227D02*
X2615432D01*
G01X2621569Y563196D02*
X2615663D01*
Y575007D01*
X2621569D01*
G01X2619207Y569298D02*
X2615663D01*
G01X2615368Y778888D02*
Y790699D01*
X2618321D01*
X2619502Y790108D01*
X2620388Y789321D01*
X2621126Y788140D01*
X2621716Y786762D01*
X2621864Y784793D01*
X2621716Y782825D01*
X2621126Y781447D01*
X2620388Y780266D01*
X2619502Y779478D01*
X2618321Y778888D01*
X2615368D01*
G01X2621864Y1005787D02*
X2620978Y1006377D01*
X2619945Y1006771D01*
X2618764D01*
X2617435Y1006180D01*
X2616402Y1005196D01*
X2615663Y1004015D01*
X2615073Y1002047D01*
X2614925Y1000275D01*
X2615220Y998503D01*
X2615663Y997322D01*
X2616549Y996141D01*
X2617583Y995354D01*
X2618616Y994960D01*
X2619649D01*
X2620683Y995354D01*
X2621569Y995944D01*
X2622307Y996731D01*
G01X2619797Y1216951D02*
X2620388Y1217542D01*
X2620830Y1218526D01*
X2621126Y1219904D01*
X2620830Y1221085D01*
X2620240Y1221872D01*
X2619207Y1222463D01*
X2615220D01*
Y1210652D01*
X2620092D01*
X2621126Y1211439D01*
X2621716Y1212620D01*
X2622012Y1213998D01*
X2621716Y1215376D01*
X2620830Y1216557D01*
X2619797Y1216951D01*
X2615220D01*
G01X2614925Y1426534D02*
X2618616Y1438345D01*
X2622307Y1426534D01*
G01X2620978Y1430668D02*
X2616254D01*
G01X-496974Y-637600D02*
Y1559093D01*
G01X2627632Y-637600D02*
X-496974D01*
G01Y-402781D02*
X-478037D01*
G01X-496974Y-186899D02*
X-478037D01*
G01X-496974D02*
X-478037D01*
G01X-496974Y28983D02*
X-478037D01*
G01X-496974D02*
X-478037D01*
G01X-496974Y244865D02*
X-478037D01*
G01X-496974D02*
X-478037D01*
G01X-496974Y460747D02*
X-478037D01*
G01X-496974D02*
X-478037D01*
G01X-496974D02*
X-478037D01*
G01X-496974Y676628D02*
X-478037D01*
G01X-496974D02*
X-478037D01*
G01X-496974Y892510D02*
X-478037D01*
G01X-496974D02*
X-478037D01*
G01X-496974Y1108392D02*
X-478037D01*
G01X-496974D02*
X-478037D01*
G01X-496974Y1324274D02*
X-478037D01*
G01X-496974Y1559093D02*
X2627632D01*
G01X-478037Y-618663D02*
Y1540156D01*
G01X2608695Y-618663D02*
X-478037D01*
G01Y1540156D02*
X2608695D01*
G01X-252686Y-618663D02*
Y-637600D01*
G01Y1559093D02*
Y1540156D01*
G01X3691Y-3937D02*
X-71867D01*
G01X577708Y47244D02*
X-71867D01*
G01X163730Y71654D02*
X-71867D01*
G01X76330Y122835D02*
X-71867D01*
G01X-70497Y134567D02*
X-71914D01*
G01X-69079Y130709D02*
X-70497Y134567D01*
G01X3691Y130709D02*
X-69079D01*
G01X577708Y181890D02*
X-71867D01*
G01X163730Y206300D02*
X-71867D01*
G01X76330Y257481D02*
X-71867D01*
G01X-69670Y268500D02*
X-71087D01*
G01X-68253Y265355D02*
X-69670Y268500D01*
G01X4478Y265355D02*
X-68253D01*
G01X577708Y316536D02*
X-71867D01*
G01X163730Y340946D02*
X-71867D01*
G01X76330Y392127D02*
X-71867D01*
G01X-69257Y405024D02*
X-70674D01*
G01X-67840Y400001D02*
X-69257Y405024D01*
G01X3691Y400001D02*
X-67840D01*
G01X577708Y451182D02*
X-71867D01*
G01X163730Y475592D02*
X-71867D01*
G01X76330Y526773D02*
X-71867D01*
G01X-69612Y537577D02*
X-71029D01*
G01X-68194Y534647D02*
X-69612Y537577D01*
G01X4478Y534647D02*
X-68194D01*
G01X577708Y585828D02*
X-71867D01*
G01X163730Y610238D02*
X-71867D01*
G01X76330Y661419D02*
X-71867D01*
G01X-70370Y672880D02*
X-71787D01*
G01X-68953Y669293D02*
X-70370Y672880D01*
G01X3691Y669293D02*
X-68953D01*
G01X577708Y720474D02*
X-71867D01*
G01X163730Y744884D02*
X-71867D01*
G01X76330Y796065D02*
X-71867D01*
G01X-71951Y808705D02*
X-73368D01*
G01X-70534Y803939D02*
X-71951Y808705D01*
G01X3691Y803939D02*
X-70534D01*
G01X577708Y855120D02*
X-71867D01*
G01X163730Y879530D02*
X-71867D01*
G01X76330Y930711D02*
X-71867D01*
G01X-33017Y-618663D02*
Y-637600D01*
G01Y1559093D02*
Y1540156D01*
G01X21260Y19685D02*
G03I-5020J0D01*
G01X28051D02*
G03I-11811J0D01*
G01X3937Y-3937D02*
X724409D01*
G01X0Y0D02*
G03X3937Y-3937I3937J0D01*
G01X0Y35433D02*
Y0D01*
G01X42607Y7795D02*
G03Y3780I0J-2008D01*
G01X48907Y1887D02*
X36307D01*
G01Y9687D02*
X48907D01*
G01X36307Y1887D02*
Y9687D01*
G01X50007Y787D02*
X35207D01*
G01Y10787D02*
X50007D01*
G01X35207Y787D02*
Y10787D01*
G01X0Y51181D02*
G03X3937Y47244I3937J0D01*
G01X0Y51181D02*
Y118898D01*
G01X4724Y47244D02*
X3937D01*
G01X29921Y63780D02*
Y47244D01*
G01X41732Y75591D02*
G03X29921Y63780I0J-11811D01*
G01X4724Y39370D02*
G03Y47244I0J3937D01*
G01X29921D02*
G03Y39370I0J-3937D01*
G01X3937D02*
G03X0Y35433I0J-3937D01*
G01X33858Y39370D02*
X3937D01*
G01X33858D02*
G03X37795Y43307I0J3937D01*
G01Y63780D02*
Y43307D01*
G01X41732Y67717D02*
G03X37795Y63780I0J-3937D01*
G01X65354Y67717D02*
X41732D01*
G01X3937Y122835D02*
G03X0Y118898I0J-3937D01*
G01X60828Y75591D02*
X41732D01*
G01X20531Y99213D02*
G03I-4291J0D01*
G01X29921Y122835D02*
X60828D01*
G01X21279Y154331D02*
G03X11201I-5039J0D01*
G01D02*
G03X21279I5039J0D01*
G01X3937Y130709D02*
X724409D01*
G01X0Y134646D02*
G03X3937Y130709I3937J0D01*
G01X0Y170079D02*
Y134646D01*
G01X4724Y122835D02*
G03Y130709I0J3937D01*
G01X29921D02*
G03Y122835I0J-3937D01*
G01X4724D02*
X3937D01*
G01X42607Y142441D02*
G03Y138426I0J-2008D01*
G01X48907Y136533D02*
X36307D01*
G01Y144333D02*
X48907D01*
G01X36307Y136533D02*
Y144333D01*
G01X50007Y135433D02*
X35207D01*
G01Y145433D02*
X50007D01*
G01X35207Y135433D02*
Y145433D01*
G01X0Y185827D02*
G03X3937Y181890I3937J0D01*
G01X0Y185827D02*
Y253544D01*
G01X4724Y181890D02*
X3937D01*
G01X29921Y198426D02*
Y181890D01*
G01X41732Y210237D02*
G03X29921Y198426I0J-11811D01*
G01X60828Y210237D02*
X41732D01*
G01X4724Y174016D02*
G03Y181890I0J3937D01*
G01X29921D02*
G03Y174016I0J-3937D01*
G01X3937D02*
G03X0Y170079I0J-3937D01*
G01X33858Y174016D02*
X3937D01*
G01X33858D02*
G03X37795Y177953I0J3937D01*
G01Y198426D02*
Y177953D01*
G01X41732Y202363D02*
G03X37795Y198426I0J-3937D01*
G01X65354Y202363D02*
X41732D01*
G01X29921Y257481D02*
X60828D01*
G01X3937D02*
G03X0Y253544I0J-3937D01*
G01X4724Y257481D02*
G03Y265355I0J3937D01*
G01X29921D02*
G03Y257481I0J-3937D01*
G01X4724D02*
X3937D01*
G01X20531Y233859D02*
G03I-4291J0D01*
G01X4724Y308662D02*
G03Y316536I0J3937D01*
G01X29921D02*
G03Y308662I0J-3937D01*
G01X21279Y288977D02*
G03X11201I-5039J0D01*
G01D02*
G03X21279I5039J0D01*
G01X3937Y265355D02*
X724409D01*
G01X0Y269292D02*
G03X3937Y265355I3937J0D01*
G01X0Y304725D02*
Y269292D01*
G01X3937Y308662D02*
G03X0Y304725I0J-3937D01*
G01X33858Y308662D02*
X3937D01*
G01X33858D02*
G03X37795Y312599I0J3937D01*
G01X42607Y277087D02*
G03Y273072I0J-2007D01*
G01X48907Y271180D02*
X36307D01*
G01Y278980D02*
X48907D01*
G01X36307Y271180D02*
Y278980D01*
G01X50007Y270080D02*
X35207D01*
G01Y280080D02*
X50007D01*
G01X35207Y270080D02*
Y280080D01*
G01X0Y320473D02*
G03X3937Y316536I3937J0D01*
G01X0Y320473D02*
Y388190D01*
G01X4724Y316536D02*
X3937D01*
G01X29921Y333072D02*
Y316536D01*
G01X41732Y344883D02*
G03X29921Y333072I0J-11811D01*
G01X60828Y344883D02*
X41732D01*
G01X37795Y333072D02*
Y312599D01*
G01X41732Y337009D02*
G03X37795Y333072I0J-3937D01*
G01X65354Y337009D02*
X41732D01*
G01X29921Y392127D02*
X60828D01*
G01X3937D02*
G03X0Y388190I0J-3937D01*
G01X4724Y392127D02*
G03Y400001I0J3937D01*
G01X29921D02*
G03Y392127I0J-3937D01*
G01X4724D02*
X3937D01*
G01X20531Y368505D02*
G03I-4291J0D01*
G01X3937Y400001D02*
X724409D01*
G01X0Y403938D02*
G03X3937Y400001I3937J0D01*
G01X0Y439371D02*
Y403938D01*
G01X48907Y405826D02*
X36307D01*
G01D02*
Y413626D01*
G01X50007Y404726D02*
X35207D01*
G01D02*
Y414726D01*
G01X0Y455119D02*
G03X3937Y451182I3937J0D01*
G01X4724D02*
X3937D01*
G01X29921Y467718D02*
Y451182D01*
G01X4724Y443308D02*
G03Y451182I0J3937D01*
G01X29921D02*
G03Y443308I0J-3937D01*
G01X21279Y423623D02*
G03X11201I-5039J0D01*
G01D02*
G03X21279I5039J0D01*
G01X3937Y443308D02*
G03X0Y439371I0J-3937D01*
G01X33858Y443308D02*
X3937D01*
G01X33858D02*
G03X37795Y447245I0J3937D01*
G01Y467718D02*
Y447245D01*
G01X42607Y411733D02*
G03Y407718I0J-2007D01*
G01X36307Y413626D02*
X48907D01*
G01X35207Y414726D02*
X50007D01*
G01X0Y455119D02*
Y522836D01*
G01X41732Y479529D02*
G03X29921Y467718I0J-11811D01*
G01X60828Y479529D02*
X41732D01*
G01X20531Y503151D02*
G03I-4291J0D01*
G01X41732Y471655D02*
G03X37795Y467718I0J-3937D01*
G01X65354Y471655D02*
X41732D01*
G01X29921Y526773D02*
X60828D01*
G01X3937D02*
G03X0Y522836I0J-3937D01*
G01X4724Y526773D02*
G03Y534647I0J3937D01*
G01X29921D02*
G03Y526773I0J-3937D01*
G01X4724D02*
X3937D01*
G01Y534647D02*
X724409D01*
G01X0Y538584D02*
G03X3937Y534647I3937J0D01*
G01X0Y574017D02*
Y538584D01*
G01X42607Y546380D02*
G03Y542364I0J-2008D01*
G01X48907Y540472D02*
X36307D01*
G01Y548272D02*
X48907D01*
G01X36307Y540472D02*
Y548272D01*
G01X50007Y539372D02*
X35207D01*
G01D02*
Y549372D01*
G01X0Y589765D02*
G03X3937Y585828I3937J0D01*
G01X0Y589765D02*
Y657482D01*
G01X4724Y585828D02*
X3937D01*
G01X29921Y602364D02*
Y585828D01*
G01X4724Y577954D02*
G03Y585828I0J3937D01*
G01X29921D02*
G03Y577954I0J-3937D01*
G01X21279Y558269D02*
G03X11201I-5039J0D01*
G01D02*
G03X21279I5039J0D01*
G01X3937Y577954D02*
G03X0Y574017I0J-3937D01*
G01X33858Y577954D02*
X3937D01*
G01X33858D02*
G03X37795Y581891I0J3937D01*
G01Y602364D02*
Y581891D01*
G01X35207Y549372D02*
X50007D01*
G01X41732Y614175D02*
G03X29921Y602364I0J-11811D01*
G01X60828Y614175D02*
X41732D01*
G01X20531Y637797D02*
G03I-4291J0D01*
G01X41732Y606301D02*
G03X37795Y602364I0J-3937D01*
G01X65354Y606301D02*
X41732D01*
G01X29921Y661419D02*
X60828D01*
G01X3937D02*
G03X0Y657482I0J-3937D01*
G01X4724Y661419D02*
G03Y669293I0J3937D01*
G01X29921D02*
G03Y661419I0J-3937D01*
G01X4724D02*
X3937D01*
G01X11201Y692915D02*
G03X21279I5039J0D01*
G01X3937Y669293D02*
X724409D01*
G01X0Y673230D02*
G03X3937Y669293I3937J0D01*
G01X0Y708663D02*
Y673230D01*
G01X42607Y681026D02*
G03Y677010I0J-2008D01*
G01X48907Y675118D02*
X36307D01*
G01Y682918D02*
X48907D01*
G01X36307Y675118D02*
Y682918D01*
G01X50007Y674018D02*
X35207D01*
G01Y684018D02*
X50007D01*
G01X35207Y674018D02*
Y684018D01*
G01X0Y724411D02*
G03X3937Y720474I3937J0D01*
G01X0Y724411D02*
Y792128D01*
G01X4724Y720474D02*
X3937D01*
G01X29921Y737010D02*
Y720474D01*
G01X41732Y748821D02*
G03X29921Y737010I0J-11811D01*
G01X4724Y712600D02*
G03Y720474I0J3937D01*
G01X29921D02*
G03Y712600I0J-3937D01*
G01X21279Y692915D02*
G03X11201I-5039J0D01*
G01X3937Y712600D02*
G03X0Y708663I0J-3937D01*
G01X33858Y712600D02*
X3937D01*
G01X33858D02*
G03X37795Y716537I0J3937D01*
G01Y737010D02*
Y716537D01*
G01X41732Y740947D02*
G03X37795Y737010I0J-3937D01*
G01X60828Y748821D02*
X41732D01*
G01X20531Y772443D02*
G03I-4291J0D01*
G01X65354Y740947D02*
X41732D01*
G01X29921Y796065D02*
X60828D01*
G01X3937D02*
G03X0Y792128I0J-3937D01*
G01X4724Y796065D02*
G03Y803939I0J3937D01*
G01X29921D02*
G03Y796065I0J-3937D01*
G01X4724D02*
X3937D01*
G01X21279Y827561D02*
G03X11201I-5039J0D01*
G01D02*
G03X21279I5039J0D01*
G01X3937Y803939D02*
X724409D01*
G01X0Y807876D02*
G03X3937Y803939I3937J0D01*
G01X0Y843309D02*
Y807876D01*
G01X42607Y815672D02*
G03Y811656I0J-2008D01*
G01X48907Y809764D02*
X36307D01*
G01Y817564D02*
X48907D01*
G01X36307Y809764D02*
Y817564D01*
G01X50007Y808664D02*
X35207D01*
G01Y818664D02*
X50007D01*
G01X35207Y808664D02*
Y818664D01*
G01X0Y843556D02*
Y964887D01*
G01Y859057D02*
G03X3937Y855120I3937J0D01*
G01X0Y859057D02*
Y922837D01*
G01X4724Y855120D02*
X3937D01*
G01X29921Y871656D02*
Y855120D01*
G01X41732Y883467D02*
G03X29921Y871656I0J-11811D01*
G01X4724Y847246D02*
G03Y855120I0J3937D01*
G01X29921D02*
G03Y847246I0J-3937D01*
G01X3937D02*
G03X0Y843309I0J-3937D01*
G01X33858Y847246D02*
X3937D01*
G01X33858D02*
G03X37795Y851183I0J3937D01*
G01Y871656D02*
Y851183D01*
G01X41732Y875593D02*
G03X37795Y871656I0J-3937D01*
G01X65354Y875593D02*
X41732D01*
G01X7874Y930711D02*
G03X0Y922837I0J-7874D01*
G01X60828Y883467D02*
X41732D01*
G01X20531Y907089D02*
G03I-4291J0D01*
G01X60828Y930711D02*
X7874D01*
G01X53445Y19685D02*
G03I-5709J0D01*
G01X42607Y3780D02*
G03Y7795I0J2008D01*
G01X48907Y9687D02*
Y1887D01*
G01X50007Y10787D02*
Y787D01*
G01X65222Y-14428D02*
X101422D01*
G01X50007Y787D02*
X65222Y-14428D01*
G01X57077Y-2748D02*
X50007Y787D01*
G01D02*
X53542Y-6283D01*
G01D02*
X57077Y-2748D01*
G01X54527Y62205D02*
G03X55709I591J0D01*
G01Y55906D02*
G03X54527I-591J0D01*
G01X52559D02*
G03X51378I-591J0D01*
G01Y62205D02*
G03X52559I590J0D01*
G01X54527D02*
G03X55709I591J0D01*
G01Y55906D02*
G03X54527I-591J0D01*
G01X52559D02*
G03X51378I-591J0D01*
G01Y62205D02*
G03X52559I590J0D01*
G01X54839Y60937D02*
X54798Y60929D01*
G01X53937Y62205D02*
X56299D01*
G01X50787D02*
X53149D01*
G01X51378D02*
X50590D01*
G01X51378D02*
X50590D01*
G01X54527D02*
X52559D01*
G01X54527D02*
X52559D01*
G01X56496D02*
X55709D01*
G01X56496D02*
X55709D01*
G01X56496Y61221D02*
X50590D01*
G01X55528Y61147D02*
X55577D01*
G01X55364D02*
X55413D01*
G01X55085D02*
X55159D01*
G01X54970D02*
X55019D01*
G01X54601D02*
X54798D01*
G01X54806Y61105D02*
X54650D01*
G01X50590Y61024D02*
X56496D01*
G01X54650Y60979D02*
X54806D01*
G01X54798Y60929D02*
X54650D01*
G01Y60753D02*
X54601D01*
G01X55577D02*
X55528D01*
G01X55413D02*
X55339D01*
G01X55134D02*
X55085D01*
G01X55019D02*
X54970D01*
G01X53149Y60630D02*
X50787D01*
G01X56299D02*
X53937D01*
G01X53149Y57480D02*
X50787D01*
G01X56299D02*
X53937D01*
G01X50590Y57087D02*
X56496D01*
G01Y56890D02*
X50590D01*
G01X55709Y55906D02*
X56496D01*
G01X55709D02*
X56496D01*
G01X53937D02*
X56299D01*
G01X52559D02*
X54527D01*
G01X52559D02*
X54527D01*
G01X50787D02*
X53149D01*
G01X50590D02*
X51378D01*
G01X50590D02*
X51378D01*
G01X54798Y61147D02*
X54839Y61139D01*
G01X54831Y61097D02*
X54806Y61105D01*
G01Y60979D02*
X54831Y60988D01*
G01X54839Y61139D02*
X54872Y61113D01*
G01X54847Y61080D02*
X54831Y61097D01*
G01X54872Y60963D02*
X54839Y60937D01*
G01X54872Y61113D02*
X54896Y61080D01*
G01X54831Y60988D02*
X54847Y61004D01*
G01X55339Y60753D02*
X55134Y61097D01*
G01X55159Y61147D02*
X55364Y60812D01*
G01X55528Y61080D02*
X55479Y61021D01*
G01Y61088D02*
X55528Y61147D01*
G01X54896Y61080D02*
X54905Y61055D01*
G01X54855D02*
X54847Y61080D01*
G01X54896Y60996D02*
X54872Y60963D01*
G01X54905Y61021D02*
X54896Y60996D01*
G01X54847Y61004D02*
X54855Y61030D01*
G01X56496Y55906D02*
Y62205D01*
G01Y55906D02*
Y62205D01*
G01X56299Y55906D02*
Y57480D01*
G01Y62205D02*
Y60630D01*
G01X55577Y61147D02*
Y60753D01*
G01X55528D02*
Y61080D01*
G01X55479Y61021D02*
Y61088D01*
G01X55413Y61147D02*
Y60753D01*
G01X55364Y60812D02*
Y61147D01*
G01X55134Y61097D02*
Y60753D01*
G01X55085D02*
Y61147D01*
G01X55019D02*
Y60753D01*
G01X54970D02*
Y61147D01*
G01X54905Y61055D02*
Y61021D01*
G01X54855Y61030D02*
Y61055D01*
G01X54650Y61105D02*
Y60979D01*
G01Y60929D02*
Y60753D01*
G01X54601D02*
Y61147D01*
G01X53937Y60630D02*
Y62205D01*
G01Y57480D02*
Y55906D01*
G01X53149D02*
Y57480D01*
G01Y62205D02*
Y60630D01*
G01X50787D02*
Y62205D01*
G01Y57480D02*
Y55906D01*
G01X50590D02*
Y62205D01*
G01D02*
Y55906D01*
G01X69291Y63780D02*
G03X65354Y67717I-3937J0D01*
G01X69291Y43307D02*
Y63780D01*
G01Y43307D02*
G03X73228Y39370I3937J0D01*
G01X156102D02*
X73228D01*
G01X64765Y118898D02*
G03X60828Y122835I-3937J0D01*
G01Y75591D02*
G03X64765Y79528I0J3937D01*
G01Y113780D02*
Y118898D01*
G01X72639Y88583D02*
G03X64765I-3937J0D01*
G01Y113780D02*
G03X72639I3937J0D01*
G01X64765Y88583D02*
Y79528D01*
G01X83879Y99213D02*
G03X93879I5000J0D01*
G01D02*
G03X83879I-5000J0D01*
G01X76576Y122835D02*
G03X72639Y118898I0J-3937D01*
G01X76576Y79528D02*
X106694D01*
G01X72639Y83465D02*
G03X76576Y79528I3937J0D01*
G01X72639Y118898D02*
Y83465D01*
G01X53445Y154331D02*
G03X42028I-5709J0D01*
G01D02*
G03X53445I5709J0D01*
G01X797048Y122835D02*
X76576D01*
G01X42607Y138426D02*
G03Y142441I0J2008D01*
G01X48907Y144333D02*
Y136533D01*
G01X50007Y145433D02*
Y135433D01*
G01X60828Y210237D02*
G03X64765Y214174I0J3937D01*
G01Y223229D02*
Y214174D01*
G01X76576D02*
X106694D01*
G01X72639Y218111D02*
G03X76576Y214174I3937J0D01*
G01X69291Y198426D02*
G03X65354Y202363I-3937J0D01*
G01X69291Y177953D02*
Y198426D01*
G01Y177953D02*
G03X73228Y174016I3937J0D01*
G01X156102D02*
X73228D01*
G01X64765Y253544D02*
G03X60828Y257481I-3937J0D01*
G01X64765Y248426D02*
Y253544D01*
G01X72639Y223229D02*
G03X64765I-3937J0D01*
G01Y248426D02*
G03X72639I3937J0D01*
G01X83879Y233859D02*
G03X93879I5000J0D01*
G01D02*
G03X83879I-5000J0D01*
G01X76576Y257481D02*
G03X72639Y253544I0J-3937D01*
G01X797048Y257481D02*
X76576D01*
G01X72639Y253544D02*
Y218111D01*
G01X53445Y288977D02*
G03X42028I-5709J0D01*
G01D02*
G03X53445I5709J0D01*
G01X69291Y312599D02*
G03X73228Y308662I3937J0D01*
G01X156102D02*
X73228D01*
G01X42607Y273072D02*
G03Y277087I0J2008D01*
G01X48907Y278980D02*
Y271180D01*
G01X50007Y280080D02*
Y270080D01*
G01X60828Y344883D02*
G03X64765Y348820I0J3937D01*
G01X72639Y357875D02*
G03X64765I-3937J0D01*
G01D02*
Y348820D01*
G01X76576D02*
X106694D01*
G01X72639Y352757D02*
G03X76576Y348820I3937J0D01*
G01X72639Y388190D02*
Y352757D01*
G01X69291Y333072D02*
G03X65354Y337009I-3937J0D01*
G01X69291Y312599D02*
Y333072D01*
G01X64765Y388190D02*
G03X60828Y392127I-3937J0D01*
G01X64765Y383072D02*
Y388190D01*
G01Y383072D02*
G03X72639I3937J0D01*
G01X83879Y368505D02*
G03X93879I5000J0D01*
G01D02*
G03X83879I-5000J0D01*
G01X76576Y392127D02*
G03X72639Y388190I0J-3937D01*
G01X797048Y392127D02*
X76576D01*
G01X48907Y413626D02*
Y405826D01*
G01X50007Y414726D02*
Y404726D01*
G01X53445Y423623D02*
G03X42028I-5709J0D01*
G01D02*
G03X53445I5709J0D01*
G01X69291Y447245D02*
Y467718D01*
G01Y447245D02*
G03X73228Y443308I3937J0D01*
G01X156102D02*
X73228D01*
G01X42607Y407718D02*
G03Y411733I0J2008D01*
G01X60828Y479529D02*
G03X64765Y483466I0J3937D01*
G01X72639Y492521D02*
G03X64765I-3937J0D01*
G01D02*
Y483466D01*
G01X83879Y503151D02*
G03X93879I5000J0D01*
G01X76576Y483466D02*
X106694D01*
G01X72639Y487403D02*
G03X76576Y483466I3937J0D01*
G01X72639Y522836D02*
Y487403D01*
G01X69291Y467718D02*
G03X65354Y471655I-3937J0D01*
G01X64765Y522836D02*
G03X60828Y526773I-3937J0D01*
G01X64765Y517718D02*
Y522836D01*
G01Y517718D02*
G03X72639I3937J0D01*
G01X93879Y503151D02*
G03X83879I-5000J0D01*
G01X76576Y526773D02*
G03X72639Y522836I0J-3937D01*
G01X797048Y526773D02*
X76576D01*
G01X42607Y542364D02*
G03Y546380I0J2008D01*
G01X48907Y548272D02*
Y540472D01*
G01X50007Y549372D02*
Y539372D01*
G01X53445Y558269D02*
G03X42028I-5709J0D01*
G01D02*
G03X53445I5709J0D01*
G01X69291Y581891D02*
Y602364D01*
G01Y581891D02*
G03X73228Y577954I3937J0D01*
G01X156102D02*
X73228D01*
G01X60828Y614175D02*
G03X64765Y618112I0J3937D01*
G01X72639Y627167D02*
G03X64765I-3937J0D01*
G01D02*
Y618112D01*
G01X83879Y637797D02*
G03X93879I5000J0D01*
G01D02*
G03X83879I-5000J0D01*
G01X76576Y618112D02*
X106694D01*
G01X72639Y622049D02*
G03X76576Y618112I3937J0D01*
G01X72639Y657482D02*
Y622049D01*
G01X69291Y602364D02*
G03X65354Y606301I-3937J0D01*
G01X64765Y657482D02*
G03X60828Y661419I-3937J0D01*
G01X64765Y652364D02*
Y657482D01*
G01Y652364D02*
G03X72639I3937J0D01*
G01X42028Y692915D02*
G03X53445I5709J0D01*
G01X76576Y661419D02*
G03X72639Y657482I0J-3937D01*
G01X797048Y661419D02*
X76576D01*
G01X42607Y677010D02*
G03Y681026I0J2008D01*
G01X48907Y682918D02*
Y675118D01*
G01X50007Y684018D02*
Y674018D01*
G01X53445Y692915D02*
G03X42028I-5709J0D01*
G01X69291Y737010D02*
G03X65354Y740947I-3937J0D01*
G01X69291Y716537D02*
Y737010D01*
G01Y716538D02*
G03X73228Y712601I3937J0D01*
G01X156102Y712600D02*
X73228D01*
G01X60828Y748821D02*
G03X64765Y752758I0J3937D01*
G01Y787010D02*
Y792128D01*
G01X72639Y761813D02*
G03X64765I-3937J0D01*
G01Y787010D02*
G03X72639I3937J0D01*
G01X64765Y761813D02*
Y752758D01*
G01X83879Y772443D02*
G03X93879I5000J0D01*
G01D02*
G03X83879I-5000J0D01*
G01X76576Y752758D02*
X106694D01*
G01X72639Y756695D02*
G03X76576Y752758I3937J0D01*
G01X72639Y792128D02*
Y756695D01*
G01X64765Y792128D02*
G03X60828Y796065I-3937J0D01*
G01X53445Y827561D02*
G03X42028I-5709J0D01*
G01D02*
G03X53445I5709J0D01*
G01X76576Y796065D02*
G03X72639Y792128I0J-3937D01*
G01X797048Y796065D02*
X76576D01*
G01X42607Y811656D02*
G03Y815672I0J2008D01*
G01X48907Y817564D02*
Y809764D01*
G01X50007Y818664D02*
Y808664D01*
G01X69291Y871656D02*
G03X65354Y875593I-3937J0D01*
G01X69291Y851183D02*
Y871656D01*
G01Y851184D02*
G03X73228Y847247I3937J0D01*
G01X156102Y847246D02*
X73228D01*
G01X72639Y927020D02*
Y964887D01*
G01X60828Y883467D02*
G03X64765Y887404I0J3937D01*
G01Y926774D02*
G03X60828Y930711I-3937J0D01*
G01X64765Y921656D02*
Y926774D01*
G01X72639Y896459D02*
G03X64765I-3937J0D01*
G01Y921656D02*
G03X72639I3937J0D01*
G01X64765Y896459D02*
Y887404D01*
G01X83879Y907089D02*
G03X93879I5000J0D01*
G01D02*
G03X83879I-5000J0D01*
G01X76576Y930711D02*
G03X72639Y926774I0J-3937D01*
G01X76576Y887404D02*
X106694D01*
G01X72639Y891341D02*
G03X76576Y887404I3937J0D01*
G01X72639Y926774D02*
Y891341D01*
G01X52411Y920770D02*
G03I-4000J0D01*
G01X50411D02*
G03I-2000J0D01*
G01X797048Y930711D02*
X76576D01*
G01X114568Y51181D02*
X138190D01*
G01X110631Y55118D02*
G03X114568Y51181I3937J0D01*
G01X110631Y75591D02*
Y55118D01*
G01X114666Y99213D02*
G03X126083I5708J0D01*
G01D02*
G03X114666I-5709J0D01*
G01X110631Y75591D02*
G03X106694Y79528I-3937J0D01*
G01X114568Y185827D02*
X138190D01*
G01X110631Y189764D02*
G03X114568Y185827I3937J0D01*
G01X110631Y210237D02*
Y189764D01*
G01Y210237D02*
G03X106694Y214174I-3937J0D01*
G01X114666Y233859D02*
G03X126083I5708J0D01*
G01D02*
G03X114666I-5709J0D01*
G01X114568Y320473D02*
X138190D01*
G01X110631Y324410D02*
G03X114568Y320473I3937J0D01*
G01X110631Y344883D02*
Y324410D01*
G01Y344883D02*
G03X106694Y348820I-3937J0D01*
G01X114666Y368505D02*
G03X126083I5708J0D01*
G01D02*
G03X114666I-5709J0D01*
G01Y503151D02*
G03X126083I5708J0D01*
G01X114568Y455119D02*
X138190D01*
G01X110631Y459056D02*
G03X114568Y455119I3937J0D01*
G01X110631Y479529D02*
Y459056D01*
G01Y479529D02*
G03X106694Y483466I-3937J0D01*
G01X126083Y503151D02*
G03X114666I-5709J0D01*
G01X114568Y589765D02*
X138190D01*
G01X110631Y593702D02*
G03X114568Y589765I3937J0D01*
G01X110631Y614175D02*
Y593702D01*
G01X114666Y637797D02*
G03X126083I5708J0D01*
G01D02*
G03X114666I-5709J0D01*
G01X110631Y614175D02*
G03X106694Y618112I-3937J0D01*
G01X114568Y724411D02*
X138190D01*
G01X110631Y728348D02*
G03X114568Y724411I3937J0D01*
G01X110631Y748821D02*
Y728348D01*
G01X114666Y772443D02*
G03X126083I5708J0D01*
G01D02*
G03X114666I-5709J0D01*
G01X110631Y748821D02*
G03X106694Y752758I-3937J0D01*
G01X114568Y859057D02*
X138190D01*
G01X110631Y862994D02*
G03X114568Y859057I3937J0D01*
G01X110631Y883467D02*
Y862994D01*
G01X114666Y907089D02*
G03X126083I5708J0D01*
G01D02*
G03X114666I-5709J0D01*
G01X110631Y883467D02*
G03X106694Y887404I-3937J0D01*
G01X178740Y62205D02*
G03X179921I591J0D01*
G01Y55906D02*
G03X178740I-590J0D01*
G01X176772D02*
G03X175590I-591J0D01*
G01Y62205D02*
G03X176772I591J0D01*
G01X178740D02*
G03X179921I591J0D01*
G01Y55906D02*
G03X178740I-590J0D01*
G01X176772D02*
G03X175590I-591J0D01*
G01Y62205D02*
G03X176772I591J0D01*
G01X179052Y60937D02*
X179011Y60929D01*
G01X178149Y62205D02*
X180512D01*
G01X175000D02*
X177362D01*
G01X175590D02*
X174803D01*
G01X175590D02*
X174803D01*
G01X178740D02*
X176772D01*
G01X178740D02*
X176772D01*
G01X180709D02*
X179921D01*
G01X180709D02*
X179921D01*
G01X180709Y61221D02*
X174803D01*
G01X179741Y61147D02*
X179790D01*
G01X179577D02*
X179626D01*
G01X179298D02*
X179371D01*
G01X179183D02*
X179232D01*
G01X178814D02*
X179011D01*
G01X179019Y61105D02*
X178863D01*
G01X174803Y61024D02*
X180709D01*
G01X178863Y60979D02*
X179019D01*
G01X179011Y60929D02*
X178863D01*
G01X179790Y60753D02*
X179741D01*
G01X179626D02*
X179552D01*
G01X179347D02*
X179298D01*
G01X179232D02*
X179183D01*
G01X178863D02*
X178814D01*
G01X177362Y60630D02*
X175000D01*
G01X180512D02*
X178149D01*
G01X177362Y57480D02*
X175000D01*
G01X180512D02*
X178149D01*
G01X174803Y57087D02*
X180709D01*
G01Y56890D02*
X174803D01*
G01X179921Y55906D02*
X180709D01*
G01X179921D02*
X180709D01*
G01X178149D02*
X180512D01*
G01X176772D02*
X178740D01*
G01X176772D02*
X178740D01*
G01X175000D02*
X177362D01*
G01X174803D02*
X175590D01*
G01X174803D02*
X175590D01*
G01X179011Y61147D02*
X179052Y61139D01*
G01X179043Y61097D02*
X179019Y61105D01*
G01X179052Y61139D02*
X179084Y61113D01*
G01X179019Y60979D02*
X179043Y60988D01*
G01X179060Y61080D02*
X179043Y61097D01*
G01X179084Y61113D02*
X179109Y61080D01*
G01X179084Y60963D02*
X179052Y60937D01*
G01X179109Y61080D02*
X179117Y61055D01*
G01X179068D02*
X179060Y61080D01*
G01X179552Y60753D02*
X179347Y61097D01*
G01X179371Y61147D02*
X179577Y60812D01*
G01X179043Y60988D02*
X179060Y61004D01*
G01X179741Y61080D02*
X179691Y61021D01*
G01Y61088D02*
X179741Y61147D01*
G01X179109Y60996D02*
X179084Y60963D01*
G01X179117Y61021D02*
X179109Y60996D01*
G01X179060Y61004D02*
X179068Y61030D01*
G01X180709Y55906D02*
Y62205D01*
G01Y55906D02*
Y62205D01*
G01X180512Y55906D02*
Y57480D01*
G01Y62205D02*
Y60630D01*
G01X179790Y61147D02*
Y60753D01*
G01X179741D02*
Y61080D01*
G01X179691Y61021D02*
Y61088D01*
G01X179626Y61147D02*
Y60753D01*
G01X179577Y60812D02*
Y61147D01*
G01X179347Y61097D02*
Y60753D01*
G01X179298D02*
Y61147D01*
G01X179232D02*
Y60753D01*
G01X179183D02*
Y61147D01*
G01X179117Y61055D02*
Y61021D01*
G01X179068Y61030D02*
Y61055D01*
G01X178863Y61105D02*
Y60979D01*
G01Y60929D02*
Y60753D01*
G01X178814D02*
Y61147D01*
G01X178149Y60630D02*
Y62205D01*
G01Y57480D02*
Y55906D01*
G01X177362D02*
Y57480D01*
G01Y62205D02*
Y60630D01*
G01X175000D02*
Y62205D01*
G01Y57480D02*
Y55906D01*
G01X174803D02*
Y62205D01*
G01D02*
Y55906D01*
G01X142127Y55118D02*
Y75591D01*
G01X138190Y51181D02*
G03X142127Y55118I0J3937D01*
G01X180905Y71654D02*
G03Y79528I0J3937D01*
G01X156102Y39370D02*
G03X160039Y43307I0J3937D01*
G01Y67717D02*
Y43307D01*
G01X163976Y71654D02*
G03X160039Y67717I0J-3937D01*
G01X223031Y71654D02*
X163976D01*
G01X146064Y79528D02*
X230906D01*
G01X146064D02*
G03X142127Y75591I0J-3937D01*
G01X146064Y214174D02*
X230906D01*
G01X146064D02*
G03X142127Y210237I0J-3937D01*
G01Y189764D02*
Y210237D01*
G01X138190Y185827D02*
G03X142127Y189764I0J3937D01*
G01X180905Y206300D02*
G03Y214174I0J3937D01*
G01X156102Y174016D02*
G03X160039Y177953I0J3937D01*
G01Y202363D02*
Y177953D01*
G01X163976Y206300D02*
G03X160039Y202363I0J-3937D01*
G01X223031Y206300D02*
X163976D01*
G01X156102Y308662D02*
G03X160039Y312599I0J3937D01*
G01X146064Y348820D02*
X230906D01*
G01X146064D02*
G03X142127Y344883I0J-3937D01*
G01Y324410D02*
Y344883D01*
G01X138190Y320473D02*
G03X142127Y324410I0J3937D01*
G01X180905Y340946D02*
G03Y348820I0J3937D01*
G01X160039Y337009D02*
Y312599D01*
G01X163976Y340946D02*
G03X160039Y337009I0J-3937D01*
G01X223031Y340946D02*
X163976D01*
G01X156102Y443308D02*
G03X160039Y447245I0J3937D01*
G01Y471655D02*
Y447245D01*
G01X146064Y483466D02*
X230906D01*
G01X146064D02*
G03X142127Y479529I0J-3937D01*
G01Y459056D02*
Y479529D01*
G01X138190Y455120D02*
G03X142127Y459057I0J3937D01*
G01X180905Y475592D02*
G03Y483466I0J3937D01*
G01X163976Y475592D02*
G03X160039Y471655I0J-3937D01*
G01X223031Y475592D02*
X163976D01*
G01X142127Y593702D02*
Y614175D01*
G01X138190Y589766D02*
G03X142127Y593703I0J3937D01*
G01X156102Y577954D02*
G03X160039Y581891I0J3937D01*
G01Y606301D02*
Y581891D01*
G01X146064Y618112D02*
X230906D01*
G01X146064D02*
G03X142127Y614175I0J-3937D01*
G01X180905Y610238D02*
G03Y618112I0J3937D01*
G01X163976Y610238D02*
G03X160039Y606301I0J-3937D01*
G01X223031Y610238D02*
X163976D01*
G01X142127Y728348D02*
Y748821D01*
G01X138190Y724412D02*
G03X142127Y728349I0J3937D01*
G01X156102Y712600D02*
G03X160039Y716537I0J3937D01*
G01Y740947D02*
Y716537D01*
G01X146064Y752758D02*
X230906D01*
G01X146064D02*
G03X142127Y748821I0J-3937D01*
G01X180905Y744884D02*
G03Y752758I0J3937D01*
G01X163976Y744884D02*
G03X160039Y740947I0J-3937D01*
G01X223031Y744884D02*
X163976D01*
G01X142127Y862994D02*
Y883467D01*
G01X138190Y859058D02*
G03X142127Y862995I0J3937D01*
G01X180905Y879530D02*
G03Y887404I0J3937D01*
G01X156102Y847246D02*
G03X160039Y851183I0J3937D01*
G01Y875593D02*
Y851183D01*
G01X163976Y879530D02*
G03X160039Y875593I0J-3937D01*
G01X223031Y879530D02*
X163976D01*
G01X146064Y887404D02*
X230906D01*
G01X146064D02*
G03X142127Y883467I0J-3937D01*
G01X186652Y-618663D02*
Y-637600D01*
G01X206102Y79528D02*
G03Y71654I0J-3937D01*
G01X226969Y67717D02*
G03X223031Y71654I-3937J0D01*
G01X226969Y43307D02*
Y67717D01*
G01Y43307D02*
G03X230906Y39370I3937J0D01*
G01X282283D02*
X230906D01*
G01X234843Y75591D02*
G03X230906Y79528I-3937J0D01*
G01X196309Y122835D02*
G03Y130709I0J3937D01*
G01X221506D02*
G03Y122835I0J-3937D01*
G01X234843Y210237D02*
G03X230906Y214174I-3937J0D01*
G01X206102D02*
G03Y206300I0J-3937D01*
G01X226969Y202363D02*
G03X223031Y206300I-3937J0D01*
G01X226969Y177953D02*
Y202363D01*
G01Y177953D02*
G03X230906Y174016I3937J0D01*
G01X282283D02*
X230906D01*
G01X196309Y257481D02*
G03Y265355I0J3937D01*
G01X221506D02*
G03Y257481I0J-3937D01*
G01X226969Y312599D02*
G03X230906Y308662I3937J0D01*
G01X282283D02*
X230906D01*
G01X234843Y344883D02*
G03X230906Y348820I-3937J0D01*
G01X206102D02*
G03Y340946I0J-3937D01*
G01X226969Y337009D02*
G03X223031Y340946I-3937J0D01*
G01X226969Y312599D02*
Y337009D01*
G01X196309Y392127D02*
G03Y400001I0J3937D01*
G01X221506D02*
G03Y392127I0J-3937D01*
G01X226969Y447245D02*
Y471655D01*
G01Y447245D02*
G03X230906Y443308I3937J0D01*
G01X282283D02*
X230906D01*
G01X234843Y479529D02*
G03X230906Y483466I-3937J0D01*
G01X206102D02*
G03Y475592I0J-3937D01*
G01X226969Y471655D02*
G03X223031Y475592I-3937J0D01*
G01X196309Y526773D02*
G03Y534647I0J3937D01*
G01X221506D02*
G03Y526773I0J-3937D01*
G01X226969Y581891D02*
Y606301D01*
G01Y581891D02*
G03X230906Y577954I3937J0D01*
G01X282283D02*
X230906D01*
G01X234843Y614175D02*
G03X230906Y618112I-3937J0D01*
G01X206102D02*
G03Y610238I0J-3937D01*
G01X226969Y606301D02*
G03X223031Y610238I-3937J0D01*
G01X196309Y661419D02*
G03Y669293I0J3937D01*
G01X221506D02*
G03Y661419I0J-3937D01*
G01X226969Y716537D02*
Y740947D01*
G01Y716537D02*
G03X230906Y712600I3937J0D01*
G01X282283D02*
X230906D01*
G01X234843Y748821D02*
G03X230906Y752758I-3937J0D01*
G01X206102D02*
G03Y744884I0J-3937D01*
G01X226969Y740947D02*
G03X223031Y744884I-3937J0D01*
G01X196309Y796065D02*
G03Y803939I0J3937D01*
G01X221506D02*
G03Y796065I0J-3937D01*
G01X206102Y887404D02*
G03Y879530I0J-3937D01*
G01X226969Y875593D02*
G03X223031Y879530I-3937J0D01*
G01X226969Y851183D02*
Y875593D01*
G01Y851183D02*
G03X230906Y847246I3937J0D01*
G01X282283D02*
X230906D01*
G01X234843Y883467D02*
G03X230906Y887404I-3937J0D01*
G01X186652Y1559093D02*
Y1540156D01*
G01X266339Y55118D02*
Y75591D01*
G01X262402Y51181D02*
G03X266339Y55118I0J3937D01*
G01X238780Y51181D02*
X262402D01*
G01X234843Y55118D02*
G03X238780Y51181I3937J0D01*
G01X234843Y75591D02*
Y55118D01*
G01X270276Y79528D02*
X355119D01*
G01X270276D02*
G03X266339Y75591I0J-3937D01*
G01X270276Y214174D02*
X355119D01*
G01X270276D02*
G03X266339Y210237I0J-3937D01*
G01Y189764D02*
Y210237D01*
G01X262402Y185827D02*
G03X266339Y189764I0J3937D01*
G01X238780Y185827D02*
X262402D01*
G01X234843Y189764D02*
G03X238780Y185827I3937J0D01*
G01X234843Y210237D02*
Y189764D01*
G01X270276Y348820D02*
X355119D01*
G01X270276D02*
G03X266339Y344883I0J-3937D01*
G01Y324410D02*
Y344883D01*
G01X262402Y320473D02*
G03X266339Y324410I0J3937D01*
G01X238780Y320473D02*
X262402D01*
G01X234843Y324410D02*
G03X238780Y320473I3937J0D01*
G01X234843Y344883D02*
Y324410D01*
G01X270276Y483466D02*
X355119D01*
G01X270276D02*
G03X266339Y479529I0J-3937D01*
G01Y459056D02*
Y479529D01*
G01X262402Y455119D02*
G03X266339Y459056I0J3937D01*
G01X238780Y455119D02*
X262402D01*
G01X234843Y459057D02*
G03X238780Y455120I3937J0D01*
G01X234843Y479529D02*
Y459056D01*
G01X266339Y593702D02*
Y614175D01*
G01X262402Y589765D02*
G03X266339Y593702I0J3937D01*
G01X238780Y589765D02*
X262402D01*
G01X234843Y593703D02*
G03X238780Y589766I3937J0D01*
G01X234843Y614175D02*
Y593702D01*
G01X270276Y618112D02*
X355119D01*
G01X270276D02*
G03X266339Y614175I0J-3937D01*
G01Y728348D02*
Y748821D01*
G01X262402Y724411D02*
G03X266339Y728348I0J3937D01*
G01X238780Y724411D02*
X262402D01*
G01X234843Y728349D02*
G03X238780Y724412I3937J0D01*
G01X234843Y748821D02*
Y728348D01*
G01X270276Y752758D02*
X355119D01*
G01X270276D02*
G03X266339Y748821I0J-3937D01*
G01Y862994D02*
Y883467D01*
G01X262402Y859057D02*
G03X266339Y862994I0J3937D01*
G01X238780Y859057D02*
X262402D01*
G01X234843Y862995D02*
G03X238780Y859058I3937J0D01*
G01X234843Y883467D02*
Y862994D01*
G01X270276Y887404D02*
X355119D01*
G01X270276D02*
G03X266339Y883467I0J-3937D01*
G01X306988Y19685D02*
G03I-5020J0D01*
G01X313779D02*
G03I-11811J0D01*
G01X302953Y62205D02*
G03X304134I590J0D01*
G01Y55906D02*
G03X302953I-591J0D01*
G01X300984D02*
G03X299803I-591J0D01*
G01Y62205D02*
G03X300984I590J0D01*
G01X302953D02*
G03X304134I590J0D01*
G01Y55906D02*
G03X302953I-591J0D01*
G01X300984D02*
G03X299803I-591J0D01*
G01Y62205D02*
G03X300984I590J0D01*
G01X302362D02*
X304724D01*
G01X299212D02*
X301575D01*
G01X299803D02*
X299016D01*
G01X299803D02*
X299016D01*
G01X302953D02*
X300984D01*
G01X302953D02*
X300984D01*
G01X304921D02*
X304134D01*
G01X304921D02*
X304134D01*
G01X303264Y60937D02*
X303223Y60929D01*
G01X303256Y61097D02*
X303231Y61105D01*
G01X303223Y61147D02*
X303264Y61139D01*
G01X304921Y61221D02*
X299016D01*
G01X303953Y61147D02*
X304002D01*
G01X303789D02*
X303838D01*
G01X303510D02*
X303584D01*
G01X303395D02*
X303445D01*
G01X303026D02*
X303223D01*
G01X303231Y61105D02*
X303076D01*
G01X299016Y61024D02*
X304921D01*
G01X303076Y60979D02*
X303231D01*
G01X303223Y60929D02*
X303076D01*
G01X304002Y60753D02*
X303953D01*
G01X303838D02*
X303765D01*
G01X303559D02*
X303510D01*
G01X303445D02*
X303395D01*
G01X303076D02*
X303026D01*
G01X301575Y60630D02*
X299212D01*
G01X304724D02*
X302362D01*
G01X301575Y57480D02*
X299212D01*
G01X304724D02*
X302362D01*
G01X299016Y57087D02*
X304921D01*
G01Y56890D02*
X299016D01*
G01X304134Y55906D02*
X304921D01*
G01X304134D02*
X304921D01*
G01X302362D02*
X304724D01*
G01X300984D02*
X302953D01*
G01X300984D02*
X302953D01*
G01X299212D02*
X301575D01*
G01X299016D02*
X299803D01*
G01X299016D02*
X299803D01*
G01X303264Y61139D02*
X303297Y61113D01*
G01X303765Y60753D02*
X303559Y61097D01*
G01X303584Y61147D02*
X303789Y60812D01*
G01X303297Y61113D02*
X303322Y61080D01*
G01X303272D02*
X303256Y61097D01*
G01X303231Y60979D02*
X303256Y60988D01*
G01X303322Y61080D02*
X303330Y61055D01*
G01X303281D02*
X303272Y61080D01*
G01X303297Y60963D02*
X303264Y60937D01*
G01X303256Y60988D02*
X303272Y61004D01*
G01X303953Y61080D02*
X303904Y61021D01*
G01Y61088D02*
X303953Y61147D01*
G01X303322Y60996D02*
X303297Y60963D01*
G01X303330Y61021D02*
X303322Y60996D01*
G01X303272Y61004D02*
X303281Y61030D01*
G01X304921Y55906D02*
Y62205D01*
G01Y55906D02*
Y62205D01*
G01X304724Y55906D02*
Y57480D01*
G01Y62205D02*
Y60630D01*
G01X304002Y61147D02*
Y60753D01*
G01X303953D02*
Y61080D01*
G01X303904Y61021D02*
Y61088D01*
G01X303838Y61147D02*
Y60753D01*
G01X303789Y60812D02*
Y61147D01*
G01X303559Y61097D02*
Y60753D01*
G01X303510D02*
Y61147D01*
G01X303445D02*
Y60753D01*
G01X303395D02*
Y61147D01*
G01X303330Y61055D02*
Y61021D01*
G01X303281Y61030D02*
Y61055D01*
G01X303076Y61105D02*
Y60979D01*
G01Y60929D02*
Y60753D01*
G01X303026D02*
Y61147D01*
G01X302362Y60630D02*
Y62205D01*
G01Y57480D02*
Y55906D01*
G01X301575D02*
Y57480D01*
G01Y62205D02*
Y60630D01*
G01X299212D02*
Y62205D01*
G01Y57480D02*
Y55906D01*
G01X299016D02*
Y62205D01*
G01D02*
Y55906D01*
G01X325788Y39370D02*
G03Y47244I0J3937D01*
G01Y71654D02*
G03Y79528I0J3937D01*
G01X325591Y71654D02*
X325788D01*
G01X325591Y47244D02*
Y71654D01*
G01X325788Y47244D02*
X325591D01*
G01X282283Y39370D02*
G03X286220Y43307I0J3937D01*
G01Y63780D02*
Y43307D01*
G01X290157Y67717D02*
G03X286220Y63780I0J-3937D01*
G01X313780Y67717D02*
X290157D01*
G01X317717Y63780D02*
G03X313780Y67717I-3937J0D01*
G01X317717Y43307D02*
Y63780D01*
G01Y43307D02*
G03X321654Y39370I3937J0D01*
G01X406496D02*
X321654D01*
G01X307265Y99213D02*
G03X317343I5039J0D01*
G01D02*
G03X307265I-5039J0D01*
G01X306969Y154331D02*
G03X296969I-5000J0D01*
G01D02*
G03X306969I5000J0D01*
G01X325788Y174016D02*
G03Y181890I0J3937D01*
G01Y206300D02*
G03Y214174I0J3937D01*
G01X325591Y206300D02*
X325788D01*
G01X325591Y181890D02*
Y206300D01*
G01X325788Y181890D02*
X325591D01*
G01X282283Y174016D02*
G03X286220Y177953I0J3937D01*
G01Y198426D02*
Y177953D01*
G01X290157Y202363D02*
G03X286220Y198426I0J-3937D01*
G01X313780Y202363D02*
X290157D01*
G01X317717Y198426D02*
G03X313780Y202363I-3937J0D01*
G01X317717Y177953D02*
Y198426D01*
G01Y177953D02*
G03X321654Y174016I3937J0D01*
G01X406496D02*
X321654D01*
G01X307265Y233859D02*
G03X317343I5039J0D01*
G01D02*
G03X307265I-5039J0D01*
G01X325788Y308662D02*
G03Y316536I0J3937D01*
G01X306969Y288977D02*
G03X296969I-5000J0D01*
G01D02*
G03X306969I5000J0D01*
G01X282283Y308662D02*
G03X286220Y312599I0J3937D01*
G01X317717D02*
G03X321654Y308662I3937J0D01*
G01X406496D02*
X321654D01*
G01X325788Y340946D02*
G03Y348820I0J3937D01*
G01X325591Y340946D02*
X325788D01*
G01X325591Y316536D02*
Y340946D01*
G01X325788Y316536D02*
X325591D01*
G01X286220Y333072D02*
Y312599D01*
G01X290157Y337009D02*
G03X286220Y333072I0J-3937D01*
G01X313780Y337009D02*
X290157D01*
G01X317717Y333072D02*
G03X313780Y337009I-3937J0D01*
G01X317717Y312599D02*
Y333072D01*
G01X307265Y368505D02*
G03X317343I5039J0D01*
G01D02*
G03X307265I-5039J0D01*
G01X325788Y443308D02*
G03Y451182I0J3937D01*
G01X325591D02*
Y475592D01*
G01X325788Y451182D02*
X325591D01*
G01X306969Y423623D02*
G03X296969I-5000J0D01*
G01D02*
G03X306969I5000J0D01*
G01X282283Y443308D02*
G03X286220Y447245I0J3937D01*
G01Y467718D02*
Y447245D01*
G01X317717D02*
Y467718D01*
G01Y447245D02*
G03X321654Y443308I3937J0D01*
G01X406496D02*
X321654D01*
G01X307265Y503151D02*
G03X317343I5039J0D01*
G01X325788Y475592D02*
G03Y483466I0J3937D01*
G01X325591Y475592D02*
X325788D01*
G01X290157Y471655D02*
G03X286220Y467718I0J-3937D01*
G01X313780Y471655D02*
X290157D01*
G01X317717Y467718D02*
G03X313780Y471655I-3937J0D01*
G01X317343Y503151D02*
G03X307265I-5039J0D01*
G01X325788Y577954D02*
G03Y585828I0J3937D01*
G01X325591D02*
Y610238D01*
G01X325788Y585828D02*
X325591D01*
G01X306969Y558269D02*
G03X296969I-5000J0D01*
G01D02*
G03X306969I5000J0D01*
G01X282283Y577954D02*
G03X286220Y581891I0J3937D01*
G01Y602364D02*
Y581891D01*
G01X317717D02*
Y602364D01*
G01Y581891D02*
G03X321654Y577954I3937J0D01*
G01X406496D02*
X321654D01*
G01X307265Y637797D02*
G03X317343I5039J0D01*
G01D02*
G03X307265I-5039J0D01*
G01X325788Y610238D02*
G03Y618112I0J3937D01*
G01X325591Y610238D02*
X325788D01*
G01X290157Y606301D02*
G03X286220Y602364I0J-3937D01*
G01X313780Y606301D02*
X290157D01*
G01X317717Y602364D02*
G03X313780Y606301I-3937J0D01*
G01X296969Y692915D02*
G03X306969I5000J0D01*
G01X325788Y712600D02*
G03Y720474I0J3937D01*
G01X325591D02*
Y744884D01*
G01X325788Y720474D02*
X325591D01*
G01X306969Y692915D02*
G03X296969I-5000J0D01*
G01X282283Y712600D02*
G03X286220Y716537I0J3937D01*
G01Y737010D02*
Y716537D01*
G01X290157Y740947D02*
G03X286220Y737010I0J-3937D01*
G01X317717Y737011D02*
G03X313780Y740947I-3937J-1D01*
G01X317717Y716537D02*
Y737010D01*
G01Y716537D02*
G03X321654Y712600I3937J0D01*
G01X406496D02*
X321654D01*
G01X307265Y772443D02*
G03X317343I5039J0D01*
G01D02*
G03X307265I-5039J0D01*
G01X325788Y744884D02*
G03Y752758I0J3937D01*
G01X325591Y744884D02*
X325788D01*
G01X313780Y740947D02*
X290157D01*
G01X306969Y827561D02*
G03X296969I-5000J0D01*
G01D02*
G03X306969I5000J0D01*
G01X325788Y847246D02*
G03Y855120I0J3937D01*
G01Y879530D02*
G03Y887404I0J3937D01*
G01X325591Y879530D02*
X325788D01*
G01X325591Y855120D02*
Y879530D01*
G01X325788Y855120D02*
X325591D01*
G01X282283Y847246D02*
G03X286220Y851183I0J3937D01*
G01Y871656D02*
Y851183D01*
G01X290157Y875593D02*
G03X286220Y871656I0J-3937D01*
G01X313780Y875593D02*
X290157D01*
G01X317717Y871657D02*
G03X313780Y875593I-3937J-1D01*
G01X317717Y851183D02*
Y871656D01*
G01Y851183D02*
G03X321654Y847246I3937J0D01*
G01X406496D02*
X321654D01*
G01X307265Y907089D02*
G03X317343I5039J0D01*
G01D02*
G03X307265I-5039J0D01*
G01X362993Y51181D02*
X386615D01*
G01X359056Y55118D02*
G03X362993Y51181I3937J0D01*
G01X359056Y75591D02*
Y55118D01*
G01X350985Y71654D02*
X351182D01*
G01X350985Y47244D02*
X351182D01*
G01X350985D02*
G03Y39370I0J-3937D01*
G01Y79528D02*
G03Y71654I0J-3937D01*
G01X351182D02*
Y47244D01*
G01X359056Y75591D02*
G03X355119Y79528I-3937J0D01*
G01X362993Y185827D02*
X386615D01*
G01X359056Y189764D02*
G03X362993Y185827I3937J0D01*
G01X359056Y210237D02*
Y189764D01*
G01Y210237D02*
G03X355119Y214174I-3937J0D01*
G01X350985Y206300D02*
X351182D01*
G01X350985Y181890D02*
X351182D01*
G01X350985D02*
G03Y174016I0J-3937D01*
G01Y214174D02*
G03Y206300I0J-3937D01*
G01X351182D02*
Y181890D01*
G01X350985Y316536D02*
G03Y308662I0J-3937D01*
G01X362993Y320473D02*
X386615D01*
G01X359056Y324410D02*
G03X362993Y320473I3937J0D01*
G01X359056Y344883D02*
Y324410D01*
G01Y344883D02*
G03X355119Y348820I-3937J0D01*
G01X350985Y340946D02*
X351182D01*
G01X350985Y316536D02*
X351182D01*
G01X350985Y348820D02*
G03Y340946I0J-3937D01*
G01X351182D02*
Y316536D01*
G01X350985Y451182D02*
X351182D01*
G01X350985D02*
G03Y443308I0J-3937D01*
G01X351182Y475592D02*
Y451182D01*
G01X362993Y455119D02*
X386615D01*
G01X359056Y459056D02*
G03X362993Y455119I3937J0D01*
G01X359056Y479529D02*
Y459056D01*
G01Y479529D02*
G03X355119Y483466I-3937J0D01*
G01X350985Y475592D02*
X351182D01*
G01X350985Y483466D02*
G03Y475592I0J-3937D01*
G01X362993Y589765D02*
X386615D01*
G01X359056Y593702D02*
G03X362993Y589765I3937J0D01*
G01X359056Y614175D02*
Y593702D01*
G01X350985Y585828D02*
X351182D01*
G01X350985D02*
G03Y577954I0J-3937D01*
G01X351182Y610238D02*
Y585828D01*
G01X359056Y614175D02*
G03X355119Y618112I-3937J0D01*
G01X350985Y610238D02*
X351182D01*
G01X350985Y618112D02*
G03Y610238I0J-3937D01*
G01X362993Y724411D02*
X386615D01*
G01X359056Y728349D02*
G03X362993Y724412I3937J0D01*
G01X359056Y748821D02*
Y728348D01*
G01X350985Y720474D02*
X351182D01*
G01X350985D02*
G03Y712600I0J-3937D01*
G01X351182Y744884D02*
Y720474D01*
G01X359056Y748821D02*
G03X355119Y752758I-3937J0D01*
G01X350985Y744884D02*
X351182D01*
G01X350985Y752758D02*
G03Y744884I0J-3937D01*
G01X362993Y859057D02*
X386615D01*
G01X359056Y862995D02*
G03X362993Y859058I3937J0D01*
G01X359056Y883467D02*
Y862994D01*
G01X350985Y879530D02*
X351182D01*
G01X350985Y855120D02*
X351182D01*
G01X350985D02*
G03Y847246I0J-3937D01*
G01Y887404D02*
G03Y879530I0J-3937D01*
G01X351182D02*
Y855120D01*
G01X359056Y883467D02*
G03X355119Y887404I-3937J0D01*
G01X406321Y-618663D02*
Y-637600D01*
G01X386904Y-618663D02*
X1568499D01*
G01X423425Y60630D02*
Y62205D01*
G01Y57480D02*
Y55906D01*
G01X423228D02*
Y62205D01*
G01D02*
Y55906D01*
G01X423425Y62205D02*
X425787D01*
G01X424016D02*
X423228D01*
G01X424016D02*
X423228D01*
G01X429134Y61221D02*
X423228D01*
G01Y61024D02*
X429134D01*
G01X425787Y60630D02*
X423425D01*
G01X425787Y57480D02*
X423425D01*
G01X423228Y57087D02*
X429134D01*
G01Y56890D02*
X423228D01*
G01X423425Y55906D02*
X425787D01*
G01X423228D02*
X424016D01*
G01X423228D02*
X424016D01*
G01X390552Y55118D02*
Y75591D01*
G01X386615Y51181D02*
G03X390552Y55118I0J3937D01*
G01X406496Y39370D02*
G03X410433Y43307I0J3937D01*
G01Y63780D02*
Y43307D01*
G01X414370Y67717D02*
G03X410433Y63780I0J-3937D01*
G01X437992Y67717D02*
X414370D01*
G01X394489Y79528D02*
X479331D01*
G01X394489D02*
G03X390552Y75591I0J-3937D01*
G01X387894Y122835D02*
G03Y130709I0J3937D01*
G01X413091D02*
G03Y122835I0J-3937D01*
G01X394489Y214174D02*
X479331D01*
G01X394489D02*
G03X390552Y210237I0J-3937D01*
G01Y189764D02*
Y210237D01*
G01X386615Y185827D02*
G03X390552Y189764I0J3937D01*
G01X406496Y174016D02*
G03X410433Y177953I0J3937D01*
G01Y198426D02*
Y177953D01*
G01X414370Y202363D02*
G03X410433Y198426I0J-3937D01*
G01X437992Y202363D02*
X414370D01*
G01X387894Y257481D02*
G03Y265355I0J3937D01*
G01X413091D02*
G03Y257481I0J-3937D01*
G01X406496Y308662D02*
G03X410433Y312599I0J3937D01*
G01X394489Y348820D02*
X479331D01*
G01X394489D02*
G03X390552Y344883I0J-3937D01*
G01Y324410D02*
Y344883D01*
G01X386615Y320473D02*
G03X390552Y324410I0J3937D01*
G01X410433Y333072D02*
Y312599D01*
G01X414370Y337009D02*
G03X410433Y333072I0J-3937D01*
G01X437992Y337009D02*
X414370D01*
G01X387894Y392127D02*
G03Y400001I0J3937D01*
G01X413091D02*
G03Y392127I0J-3937D01*
G01X406496Y443308D02*
G03X410433Y447245I0J3937D01*
G01Y467718D02*
Y447245D01*
G01X394489Y483466D02*
X479331D01*
G01X394489D02*
G03X390552Y479529I0J-3937D01*
G01Y459056D02*
Y479529D01*
G01X386615Y455119D02*
G03X390552Y459056I0J3937D01*
G01X414370Y471655D02*
G03X410433Y467718I0J-3937D01*
G01X437992Y471655D02*
X414370D01*
G01X387894Y526773D02*
G03Y534647I0J3937D01*
G01X413091D02*
G03Y526773I0J-3937D01*
G01X390552Y593702D02*
Y614175D01*
G01X386615Y589765D02*
G03X390552Y593702I0J3937D01*
G01X406496Y577954D02*
G03X410433Y581891I0J3937D01*
G01Y602364D02*
Y581891D01*
G01X394489Y618112D02*
X479331D01*
G01X394489D02*
G03X390552Y614175I0J-3937D01*
G01X414370Y606301D02*
G03X410433Y602364I0J-3937D01*
G01X437992Y606301D02*
X414370D01*
G01X387894Y661419D02*
G03Y669293I0J3937D01*
G01X413091D02*
G03Y661419I0J-3937D01*
G01X390552Y728348D02*
Y748821D01*
G01X386615Y724412D02*
G03X390552Y728349I0J3937D01*
G01X406496Y712600D02*
G03X410433Y716537I0J3937D01*
G01Y737010D02*
Y716537D01*
G01X414370Y740947D02*
G03X410433Y737010I0J-3937D01*
G01X394489Y752758D02*
X479331D01*
G01X394489D02*
G03X390552Y748821I0J-3937D01*
G01X437992Y740947D02*
X414370D01*
G01X387894Y796065D02*
G03Y803939I0J3937D01*
G01X413091D02*
G03Y796065I0J-3937D01*
G01X390552Y862994D02*
Y883467D01*
G01X386615Y859058D02*
G03X390552Y862995I0J3937D01*
G01X406496Y847246D02*
G03X410433Y851183I0J3937D01*
G01Y871656D02*
Y851183D01*
G01X414370Y875593D02*
G03X410433Y871656I0J-3937D01*
G01X437992Y875593D02*
X414370D01*
G01X394489Y887404D02*
X479331D01*
G01X394489D02*
G03X390552Y883467I0J-3937D01*
G01X406321Y1559093D02*
Y1540156D01*
G01X427165Y62205D02*
G03X428346I591J0D01*
G01Y55906D02*
G03X427165I-590J0D01*
G01X425197D02*
G03X424016I-591J0D01*
G01Y62205D02*
G03X425197I590J0D01*
G01X427165D02*
G03X428346I591J0D01*
G01Y55906D02*
G03X427165I-590J0D01*
G01X425197D02*
G03X424016I-591J0D01*
G01Y62205D02*
G03X425197I590J0D01*
G01X427534Y61080D02*
X427542Y61055D01*
G01X427493D02*
X427485Y61080D01*
G01X427977Y60753D02*
X427772Y61097D01*
G01X427797Y61147D02*
X428002Y60812D01*
G01X427510Y61113D02*
X427534Y61080D01*
G01X427485D02*
X427469Y61097D01*
G01X427477Y61139D02*
X427510Y61113D01*
G01X429134Y55906D02*
Y62205D01*
G01Y55906D02*
Y62205D01*
G01X428937Y55906D02*
Y57480D01*
G01Y62205D02*
Y60630D01*
G01X428215Y61147D02*
Y60753D01*
G01X428166D02*
Y61080D01*
G01X428117Y61021D02*
Y61088D01*
G01X428051Y61147D02*
Y60753D01*
G01X428002Y60812D02*
Y61147D01*
G01X427772Y61097D02*
Y60753D01*
G01X427723D02*
Y61147D01*
G01X427657D02*
Y60753D01*
G01X427608D02*
Y61147D01*
G01X427542Y61055D02*
Y61021D01*
G01X427493Y61030D02*
Y61055D01*
G01X427288Y61105D02*
Y60979D01*
G01Y60929D02*
Y60753D01*
G01X427239D02*
Y61147D01*
G01X426575Y60630D02*
Y62205D01*
G01Y57480D02*
Y55906D01*
G01X425787D02*
Y57480D01*
G01Y62205D02*
Y60630D01*
G01X427469Y61097D02*
X427444Y61105D01*
G01X427436Y61147D02*
X427477Y61139D01*
G01X426575Y62205D02*
X428937D01*
G01X427165D02*
X425197D01*
G01X427165D02*
X425197D01*
G01X429134D02*
X428346D01*
G01X429134D02*
X428346D01*
G01X428166Y61080D02*
X428117Y61021D01*
G01Y61088D02*
X428166Y61147D01*
G01X427534Y60996D02*
X427510Y60963D01*
G01X427542Y61021D02*
X427534Y60996D01*
G01X427485Y61004D02*
X427493Y61030D01*
G01X428166Y61147D02*
X428215D01*
G01X428002D02*
X428051D01*
G01X427723D02*
X427797D01*
G01X427608D02*
X427657D01*
G01X427239D02*
X427436D01*
G01X427444Y61105D02*
X427288D01*
G01Y60979D02*
X427444D01*
G01X427436Y60929D02*
X427288D01*
G01X428215Y60753D02*
X428166D01*
G01X428051D02*
X427977D01*
G01X427772D02*
X427723D01*
G01X427657D02*
X427608D01*
G01X427288D02*
X427239D01*
G01X428937Y60630D02*
X426575D01*
G01X428937Y57480D02*
X426575D01*
G01X428346Y55906D02*
X429134D01*
G01X428346D02*
X429134D01*
G01X426575D02*
X428937D01*
G01X425197D02*
X427165D01*
G01X425197D02*
X427165D01*
G01X427477Y60937D02*
X427436Y60929D01*
G01X427510Y60963D02*
X427477Y60937D01*
G01X427469Y60988D02*
X427485Y61004D01*
G01X427444Y60979D02*
X427469Y60988D01*
G01X450000Y47244D02*
X449803D01*
G01X450000Y71654D02*
X449803D01*
G01X450000D02*
G03Y79528I0J3937D01*
G01Y39370D02*
G03Y47244I0J3937D01*
G01X449803D02*
Y71654D01*
G01X441929Y63780D02*
G03X437992Y67717I-3937J0D01*
G01X441929Y43307D02*
Y63780D01*
G01Y43307D02*
G03X445866Y39370I3937J0D01*
G01X530709D02*
X445866D01*
G01X450000Y181890D02*
X449803D01*
G01X450000Y206300D02*
X449803D01*
G01X450000D02*
G03Y214174I0J3937D01*
G01Y174016D02*
G03Y181890I0J3937D01*
G01X449803D02*
Y206300D01*
G01X441929Y198426D02*
G03X437992Y202363I-3937J0D01*
G01X441929Y177953D02*
Y198426D01*
G01Y177953D02*
G03X445866Y174016I3937J0D01*
G01X530709D02*
X445866D01*
G01X450000Y308662D02*
G03Y316536I0J3937D01*
G01X441929Y312599D02*
G03X445866Y308662I3937J0D01*
G01X530709D02*
X445866D01*
G01X450000Y316536D02*
X449803D01*
G01X450000Y340946D02*
X449803D01*
G01X450000D02*
G03Y348820I0J3937D01*
G01X449803Y316536D02*
Y340946D01*
G01X441929Y333072D02*
G03X437992Y337009I-3937J0D01*
G01X441929Y312599D02*
Y333072D01*
G01X450000Y451182D02*
X449803D01*
G01X450000Y443308D02*
G03Y451182I0J3937D01*
G01X449803D02*
Y475592D01*
G01X441929Y447245D02*
Y467718D01*
G01Y447245D02*
G03X445866Y443308I3937J0D01*
G01X530709D02*
X445866D01*
G01X450000Y475592D02*
X449803D01*
G01X450000D02*
G03Y483466I0J3937D01*
G01X441929Y467718D02*
G03X437992Y471655I-3937J0D01*
G01X450000Y585828D02*
X449803D01*
G01X450000Y577954D02*
G03Y585828I0J3937D01*
G01X449803D02*
Y610238D01*
G01X441929Y581891D02*
Y602364D01*
G01Y581891D02*
G03X445866Y577954I3937J0D01*
G01X530709D02*
X445866D01*
G01X450000Y610238D02*
X449803D01*
G01X450000D02*
G03Y618112I0J3937D01*
G01X441929Y602364D02*
G03X437992Y606301I-3937J0D01*
G01X450000Y720474D02*
X449803D01*
G01X450000Y712600D02*
G03Y720474I0J3937D01*
G01X449803D02*
Y744884D01*
G01X441929Y737010D02*
G03X437992Y740947I-3937J0D01*
G01X441929Y716537D02*
Y737010D01*
G01Y716537D02*
G03X445866Y712600I3937J0D01*
G01X530709D02*
X445866D01*
G01X450000Y744884D02*
X449803D01*
G01X450000D02*
G03Y752758I0J3937D01*
G01Y855120D02*
X449803D01*
G01X450000Y879530D02*
X449803D01*
G01X450000D02*
G03Y887404I0J3937D01*
G01Y847246D02*
G03Y855120I0J3937D01*
G01X449803D02*
Y879530D01*
G01X441929Y871656D02*
G03X437992Y875593I-3937J0D01*
G01X441929Y851183D02*
Y871656D01*
G01Y851183D02*
G03X445866Y847246I3937J0D01*
G01X530709D02*
X445866D01*
G01X493701Y19685D02*
G03I-5020J0D01*
G01X500492D02*
G03I-11811J0D01*
G01X514765Y55118D02*
Y75591D01*
G01X510828Y51181D02*
G03X514765Y55118I0J3937D01*
G01X487205Y51181D02*
X510828D01*
G01X483269Y55118D02*
G03X487205Y51182I3937J1D01*
G01X483268Y75591D02*
Y55118D01*
G01X475197Y79528D02*
G03Y71654I0J-3937D01*
G01Y47244D02*
G03Y39370I0J-3937D01*
G01X475394Y47244D02*
X475197D01*
G01X475394Y71654D02*
Y47244D01*
G01X475197Y71654D02*
X475394D01*
G01X494017Y99213D02*
G03X504017I5000J0D01*
G01D02*
G03X494017I-5000J0D01*
G01X518702Y79528D02*
X570079D01*
G01X518702D02*
G03X514765Y75591I0J-3937D01*
G01X483268D02*
G03X479331Y79528I-3937J0D01*
G01X493720Y154331D02*
G03X483642I-5039J0D01*
G01D02*
G03X493720I5039J0D01*
G01X518702Y214174D02*
X570079D01*
G01X518702D02*
G03X514765Y210237I0J-3937D01*
G01Y189764D02*
Y210237D01*
G01X510828Y185827D02*
G03X514765Y189764I0J3937D01*
G01X487205Y185827D02*
X510828D01*
G01X483269Y189764D02*
G03X487205Y185828I3937J1D01*
G01X483268Y210237D02*
Y189764D01*
G01Y210237D02*
G03X479331Y214174I-3937J0D01*
G01X475197D02*
G03Y206300I0J-3937D01*
G01Y181890D02*
G03Y174016I0J-3937D01*
G01X475394Y181890D02*
X475197D01*
G01X475394Y206300D02*
Y181890D01*
G01X475197Y206300D02*
X475394D01*
G01X494017Y233859D02*
G03X504017I5000J0D01*
G01D02*
G03X494017I-5000J0D01*
G01X475197Y316536D02*
G03Y308662I0J-3937D01*
G01X493720Y288977D02*
G03X483642I-5039J0D01*
G01D02*
G03X493720I5039J0D01*
G01X518702Y348820D02*
X570079D01*
G01X518702D02*
G03X514765Y344883I0J-3937D01*
G01Y324410D02*
Y344883D01*
G01X510828Y320473D02*
G03X514765Y324410I0J3937D01*
G01X487205Y320473D02*
X510828D01*
G01X483269Y324410D02*
G03X487205Y320474I3937J1D01*
G01X483268Y344883D02*
Y324410D01*
G01Y344883D02*
G03X479331Y348820I-3937J0D01*
G01X475197D02*
G03Y340946I0J-3937D01*
G01X475394Y316536D02*
X475197D01*
G01X475394Y340946D02*
Y316536D01*
G01X475197Y340946D02*
X475394D01*
G01X494017Y368505D02*
G03X504017I5000J0D01*
G01D02*
G03X494017I-5000J0D01*
G01X475197Y451182D02*
G03Y443308I0J-3937D01*
G01X475394Y451182D02*
X475197D01*
G01X475394Y475592D02*
Y451182D01*
G01X493720Y423623D02*
G03X483642I-5039J0D01*
G01D02*
G03X493720I5039J0D01*
G01X494017Y503151D02*
G03X504017I5000J0D01*
G01X518702Y483466D02*
X570079D01*
G01X518702D02*
G03X514765Y479529I0J-3937D01*
G01Y459056D02*
Y479529D01*
G01X510828Y455120D02*
G03X514765Y459057I0J3937D01*
G01X487205Y455119D02*
X510828D01*
G01X483269Y459056D02*
G03X487205Y455120I3937J1D01*
G01X483268Y479529D02*
Y459056D01*
G01Y479529D02*
G03X479331Y483466I-3937J0D01*
G01X475197D02*
G03Y475592I0J-3937D01*
G01D02*
X475394D01*
G01X504017Y503151D02*
G03X494017I-5000J0D01*
G01X514765Y593702D02*
Y614175D01*
G01X510828Y589766D02*
G03X514765Y593703I0J3937D01*
G01X487205Y589765D02*
X510828D01*
G01X483269Y593702D02*
G03X487205Y589766I3937J1D01*
G01X483268Y614175D02*
Y593702D01*
G01X475197Y585828D02*
G03Y577954I0J-3937D01*
G01X475394Y585828D02*
X475197D01*
G01X475394Y610238D02*
Y585828D01*
G01X493720Y558269D02*
G03X483642I-5039J0D01*
G01D02*
G03X493720I5039J0D01*
G01X494017Y637797D02*
G03X504017I5000J0D01*
G01D02*
G03X494017I-5000J0D01*
G01X518702Y618112D02*
X570079D01*
G01X518702D02*
G03X514765Y614175I0J-3937D01*
G01X483268D02*
G03X479331Y618112I-3937J0D01*
G01X475197D02*
G03Y610238I0J-3937D01*
G01D02*
X475394D01*
G01X483642Y692915D02*
G03X493720I5039J0D01*
G01X514765Y728348D02*
Y748821D01*
G01X510828Y724412D02*
G03X514765Y728349I0J3937D01*
G01X487205Y724411D02*
X510828D01*
G01X483269Y728348D02*
G03X487205Y724412I3937J1D01*
G01X483268Y748821D02*
Y728348D01*
G01X475197Y720474D02*
G03Y712600I0J-3937D01*
G01X475394Y720474D02*
X475197D01*
G01X475394Y744884D02*
Y720474D01*
G01X493720Y692915D02*
G03X483642I-5039J0D01*
G01X494017Y772443D02*
G03X504017I5000J0D01*
G01D02*
G03X494017I-5000J0D01*
G01X518702Y752758D02*
X570079D01*
G01X518702D02*
G03X514765Y748821I0J-3937D01*
G01X483268D02*
G03X479331Y752758I-3937J0D01*
G01X475197D02*
G03Y744884I0J-3937D01*
G01D02*
X475394D01*
G01X493720Y827561D02*
G03X483642I-5039J0D01*
G01D02*
G03X493720I5039J0D01*
G01X514765Y862994D02*
Y883467D01*
G01X510828Y859058D02*
G03X514765Y862995I0J3937D01*
G01X487205Y859057D02*
X510828D01*
G01X483269Y862994D02*
G03X487205Y859058I3937J1D01*
G01X483268Y883467D02*
Y862994D01*
G01X475197Y887404D02*
G03Y879530I0J-3937D01*
G01Y855120D02*
G03Y847246I0J-3937D01*
G01X475394Y855120D02*
X475197D01*
G01X475394Y879530D02*
Y855120D01*
G01X475197Y879530D02*
X475394D01*
G01X494017Y907089D02*
G03X504017I5000J0D01*
G01D02*
G03X494017I-5000J0D01*
G01X518702Y887404D02*
X570079D01*
G01X518702D02*
G03X514765Y883467I0J-3937D01*
G01X483268D02*
G03X479331Y887404I-3937J0D01*
G01X551378Y62205D02*
G03X552559I591J0D01*
G01Y55906D02*
G03X551378I-590J0D01*
G01X549409D02*
G03X548228I-590J0D01*
G01Y62205D02*
G03X549409I591J0D01*
G01X551378D02*
G03X552559I591J0D01*
G01Y55906D02*
G03X551378I-590J0D01*
G01X549409D02*
G03X548228I-590J0D01*
G01Y62205D02*
G03X549409I591J0D01*
G01X551747Y61080D02*
X551755Y61055D01*
G01X551706D02*
X551698Y61080D01*
G01X552190Y60753D02*
X551985Y61097D01*
G01X552009Y61147D02*
X552214Y60812D01*
G01X553346Y55906D02*
Y62205D01*
G01Y55906D02*
Y62205D01*
G01X553149Y55906D02*
Y57480D01*
G01Y62205D02*
Y60630D01*
G01X552428Y61147D02*
Y60753D01*
G01X552378D02*
Y61080D01*
G01X552329Y61021D02*
Y61088D01*
G01X552264Y61147D02*
Y60753D01*
G01X552214Y60812D02*
Y61147D01*
G01X551985Y61097D02*
Y60753D01*
G01X551935D02*
Y61147D01*
G01X551870D02*
Y60753D01*
G01X551821D02*
Y61147D01*
G01X551755Y61055D02*
Y61021D01*
G01X551706Y61030D02*
Y61055D01*
G01X551501Y61105D02*
Y60979D01*
G01Y60929D02*
Y60753D01*
G01X551452D02*
Y61147D01*
G01X550787Y60630D02*
Y62205D01*
G01Y57480D02*
Y55906D01*
G01X550000D02*
Y57480D01*
G01Y62205D02*
Y60630D01*
G01X547638D02*
Y62205D01*
G01Y57480D02*
Y55906D01*
G01X547441D02*
Y62205D01*
G01D02*
Y55906D01*
G01X551722Y61113D02*
X551747Y61080D01*
G01X551698D02*
X551681Y61097D01*
G01X551755Y61021D02*
X551747Y60996D01*
G01X551698Y61004D02*
X551706Y61030D01*
G01X551689Y61139D02*
X551722Y61113D01*
G01X552378Y61080D02*
X552329Y61021D01*
G01Y61088D02*
X552378Y61147D01*
G01X551747Y60996D02*
X551722Y60963D01*
G01X551681Y60988D02*
X551698Y61004D01*
G01X551681Y61097D02*
X551657Y61105D01*
G01X551722Y60963D02*
X551689Y60937D01*
G01X551648Y61147D02*
X551689Y61139D01*
G01X550787Y62205D02*
X553149D01*
G01X547638D02*
X550000D01*
G01X548228D02*
X547441D01*
G01X548228D02*
X547441D01*
G01X551378D02*
X549409D01*
G01X551378D02*
X549409D01*
G01X553346D02*
X552559D01*
G01X553346D02*
X552559D01*
G01X551657Y60979D02*
X551681Y60988D01*
G01X553346Y61221D02*
X547441D01*
G01X552378Y61147D02*
X552428D01*
G01X552214D02*
X552264D01*
G01X551935D02*
X552009D01*
G01X551821D02*
X551870D01*
G01X551452D02*
X551648D01*
G01X551657Y61105D02*
X551501D01*
G01X547441Y61024D02*
X553346D01*
G01X551501Y60979D02*
X551657D01*
G01X551648Y60929D02*
X551501D01*
G01X552428Y60753D02*
X552378D01*
G01X552264D02*
X552190D01*
G01X551985D02*
X551935D01*
G01X551870D02*
X551821D01*
G01X551501D02*
X551452D01*
G01X550000Y60630D02*
X547638D01*
G01X553149D02*
X550787D01*
G01X550000Y57480D02*
X547638D01*
G01X553149D02*
X550787D01*
G01X547441Y57087D02*
X553346D01*
G01Y56890D02*
X547441D01*
G01X550787Y55906D02*
X553149D01*
G01X552559D02*
X553346D01*
G01X552559D02*
X553346D01*
G01X549409D02*
X551378D01*
G01X549409D02*
X551378D01*
G01X547638D02*
X550000D01*
G01X547441D02*
X548228D01*
G01X547441D02*
X548228D01*
G01X551689Y60937D02*
X551648Y60929D01*
G01X530709Y39370D02*
G03X534646Y43307I0J3937D01*
G01Y63780D02*
Y43307D01*
G01X538583Y67717D02*
G03X534646Y63780I0J-3937D01*
G01X562205Y67717D02*
X538583D01*
G01X566142Y63780D02*
G03X562205Y67717I-3937J0D01*
G01X566142Y43307D02*
Y63780D01*
G01Y43307D02*
G03X570079Y39370I3937J0D01*
G01X530709Y174016D02*
G03X534646Y177953I0J3937D01*
G01Y198426D02*
Y177953D01*
G01X538583Y202363D02*
G03X534646Y198426I0J-3937D01*
G01X562205Y202363D02*
X538583D01*
G01X566142Y198426D02*
G03X562205Y202363I-3937J0D01*
G01X566142Y177953D02*
Y198426D01*
G01Y177953D02*
G03X570079Y174016I3937J0D01*
G01X530709Y308662D02*
G03X534646Y312599I0J3937D01*
G01Y333072D02*
Y312599D01*
G01X538583Y337009D02*
G03X534646Y333072I0J-3937D01*
G01X562205Y337009D02*
X538583D01*
G01X566142Y333072D02*
G03X562205Y337009I-3937J0D01*
G01X566142Y312599D02*
Y333072D01*
G01Y312599D02*
G03X570079Y308662I3937J0D01*
G01X530709Y443308D02*
G03X534646Y447245I0J3937D01*
G01Y467718D02*
Y447245D01*
G01X566142D02*
Y467718D01*
G01Y447245D02*
G03X570079Y443308I3937J0D01*
G01X538583Y471655D02*
G03X534646Y467718I0J-3937D01*
G01X562205Y471655D02*
X538583D01*
G01X566142Y467718D02*
G03X562205Y471655I-3937J0D01*
G01X530709Y577954D02*
G03X534646Y581891I0J3937D01*
G01Y602364D02*
Y581891D01*
G01X566142D02*
Y602364D01*
G01Y581891D02*
G03X570079Y577954I3937J0D01*
G01X538583Y606301D02*
G03X534646Y602364I0J-3937D01*
G01X562205Y606301D02*
X538583D01*
G01X566142Y602364D02*
G03X562205Y606301I-3937J0D01*
G01X530709Y712601D02*
G03X534646Y716538I0J3937D01*
G01Y737010D02*
Y716537D01*
G01X538583Y740947D02*
G03X534646Y737010I0J-3937D01*
G01X566142D02*
G03X562205Y740947I-3937J0D01*
G01X566142Y716537D02*
Y737010D01*
G01Y716537D02*
G03X570079Y712600I3937J0D01*
G01X562205Y740947D02*
X538583D01*
G01X530709Y847247D02*
G03X534646Y851184I0J3937D01*
G01Y871656D02*
Y851183D01*
G01X538583Y875593D02*
G03X534646Y871656I0J-3937D01*
G01X562205Y875593D02*
X538583D01*
G01X566142Y871656D02*
G03X562205Y875593I-3937J0D01*
G01X566142Y851183D02*
Y871656D01*
G01Y851183D02*
G03X570079Y847246I3937J0D01*
G01X577954Y47244D02*
X637009D01*
G01X574016Y51181D02*
G03X577954Y47244I3937J0D01*
G01X574016Y75591D02*
Y51181D01*
G01X594883Y39370D02*
G03Y47244I0J3937D01*
G01X654921Y39370D02*
X570079D01*
G01X574016Y75591D02*
G03X570079Y79528I-3937J0D01*
G01X604676Y130709D02*
G03Y122835I0J-3937D01*
G01X579479D02*
G03Y130709I0J3937D01*
G01X577954Y181890D02*
X637009D01*
G01X574016Y185827D02*
G03X577954Y181890I3937J0D01*
G01X574016Y210237D02*
Y185827D01*
G01Y210237D02*
G03X570079Y214174I-3937J0D01*
G01X594883Y174016D02*
G03Y181890I0J3937D01*
G01X654921Y174016D02*
X570079D01*
G01X604676Y265355D02*
G03Y257481I0J-3937D01*
G01X579479D02*
G03Y265355I0J3937D01*
G01X594883Y308662D02*
G03Y316536I0J3937D01*
G01X654921Y308662D02*
X570079D01*
G01X577954Y316536D02*
X637009D01*
G01X574016Y320473D02*
G03X577954Y316536I3937J0D01*
G01X574016Y344883D02*
Y320473D01*
G01Y344883D02*
G03X570079Y348820I-3937J0D01*
G01X604676Y400001D02*
G03Y392127I0J-3937D01*
G01X579479D02*
G03Y400001I0J3937D01*
G01X577954Y451182D02*
X637009D01*
G01X574016Y455120D02*
G03X577954Y451183I3937J0D01*
G01X594883Y443308D02*
G03Y451182I0J3937D01*
G01X654921Y443308D02*
X570079D01*
G01X574016Y479529D02*
Y455119D01*
G01Y479529D02*
G03X570079Y483466I-3937J0D01*
G01X604676Y534647D02*
G03Y526773I0J-3937D01*
G01X579479D02*
G03Y534647I0J3937D01*
G01X577954Y585828D02*
X637009D01*
G01X574016Y589766D02*
G03X577954Y585829I3937J0D01*
G01X574016Y614175D02*
Y589765D01*
G01X594883Y577954D02*
G03Y585828I0J3937D01*
G01X654921Y577954D02*
X570079D01*
G01X574016Y614175D02*
G03X570079Y618112I-3937J0D01*
G01X604676Y669293D02*
G03Y661419I0J-3937D01*
G01X579479D02*
G03Y669293I0J3937D01*
G01X577954Y720474D02*
X637009D01*
G01X574016Y724412D02*
G03X577954Y720475I3937J0D01*
G01X574016Y748821D02*
Y724411D01*
G01X594883Y712600D02*
G03Y720474I0J3937D01*
G01X654921Y712600D02*
X570079D01*
G01X574016Y748821D02*
G03X570079Y752758I-3937J0D01*
G01X604676Y803939D02*
G03Y796065I0J-3937D01*
G01X579479D02*
G03Y803939I0J3937D01*
G01X577954Y855120D02*
X637009D01*
G01X574016Y859058D02*
G03X577954Y855121I3937J0D01*
G01X574016Y883467D02*
Y859057D01*
G01X594883Y847246D02*
G03Y855120I0J3937D01*
G01X654921Y847246D02*
X570079D01*
G01X574016Y883467D02*
G03X570079Y887404I-3937J0D01*
G01X625991Y-618663D02*
Y-637600D01*
G01X640946Y51181D02*
Y75591D01*
G01X637009Y47244D02*
G03X640946Y51181I0J3937D01*
G01X620080Y47244D02*
G03Y39370I0J-3937D01*
G01X654921D02*
G03X658858Y43307I0J3937D01*
G01Y63780D02*
Y43307D01*
G01X662795Y67717D02*
G03X658858Y63780I0J-3937D01*
G01X644883Y79528D02*
X727757D01*
G01X644883D02*
G03X640946Y75591I0J-3937D01*
G01X644883Y214174D02*
X727757D01*
G01X644883D02*
G03X640946Y210237I0J-3937D01*
G01Y185827D02*
Y210237D01*
G01X637009Y181890D02*
G03X640946Y185827I0J3937D01*
G01X620080Y181890D02*
G03Y174016I0J-3937D01*
G01X654921D02*
G03X658858Y177953I0J3937D01*
G01Y198426D02*
Y177953D01*
G01X662795Y202363D02*
G03X658858Y198426I0J-3937D01*
G01X620080Y316536D02*
G03Y308662I0J-3937D01*
G01X654921D02*
G03X658858Y312599I0J3937D01*
G01X644883Y348820D02*
X727757D01*
G01X644883D02*
G03X640946Y344883I0J-3937D01*
G01Y320473D02*
Y344883D01*
G01X637009Y316536D02*
G03X640946Y320473I0J3937D01*
G01X658858Y333072D02*
Y312599D01*
G01X662795Y337009D02*
G03X658858Y333072I0J-3937D01*
G01X637009Y451183D02*
G03X640946Y455120I0J3937D01*
G01X620080Y451182D02*
G03Y443308I0J-3937D01*
G01X654921D02*
G03X658858Y447245I0J3937D01*
G01Y467718D02*
Y447245D01*
G01X644883Y483466D02*
X727757D01*
G01X644883D02*
G03X640946Y479529I0J-3937D01*
G01Y455119D02*
Y479529D01*
G01X662795Y471655D02*
G03X658858Y467718I0J-3937D01*
G01X640946Y589765D02*
Y614175D01*
G01X637009Y585829D02*
G03X640946Y589766I0J3937D01*
G01X620080Y585828D02*
G03Y577954I0J-3937D01*
G01X654921D02*
G03X658858Y581891I0J3937D01*
G01Y602364D02*
Y581891D01*
G01X644883Y618112D02*
X727757D01*
G01X644883D02*
G03X640946Y614175I0J-3937D01*
G01X662795Y606301D02*
G03X658858Y602364I0J-3937D01*
G01X640946Y724411D02*
Y748821D01*
G01X637009Y720475D02*
G03X640946Y724412I0J3937D01*
G01X620080Y720474D02*
G03Y712600I0J-3937D01*
G01X654921D02*
G03X658858Y716537I0J3937D01*
G01Y737010D02*
Y716537D01*
G01X662795Y740947D02*
G03X658858Y737010I0J-3937D01*
G01X644883Y752758D02*
X727757D01*
G01X644883D02*
G03X640946Y748821I0J-3937D01*
G01Y859057D02*
Y883467D01*
G01X637009Y855121D02*
G03X640946Y859058I0J3937D01*
G01X620080Y855120D02*
G03Y847246I0J-3937D01*
G01X654921D02*
G03X658858Y851183I0J3937D01*
G01Y871656D02*
Y851183D01*
G01X662795Y875593D02*
G03X658858Y871656I0J-3937D01*
G01X644883Y887404D02*
X727757D01*
G01X644883D02*
G03X640946Y883467I0J-3937D01*
G01X625991Y1559093D02*
Y1540156D01*
G01X717126Y19685D02*
G03I-5020J0D01*
G01X686319D02*
G03I-5709J0D01*
G01X723917D02*
G03I-11811J0D01*
G01X701969Y47244D02*
X698228D01*
G01X701969Y39370D02*
G03Y47244I0J3937D01*
G01Y71654D02*
G03Y79528I0J3937D01*
G01X698228Y71654D02*
X701969D01*
G01X698228Y47244D02*
Y71654D01*
G01X675590Y62205D02*
G03X676772I591J0D01*
G01Y55906D02*
G03X675590I-591J0D01*
G01X673622D02*
G03X672441I-591J0D01*
G01Y62205D02*
G03X673622I591J0D01*
G01X675590D02*
G03X676772I591J0D01*
G01Y55906D02*
G03X675590I-591J0D01*
G01X673622D02*
G03X672441I-591J0D01*
G01Y62205D02*
G03X673622I591J0D01*
G01X675959Y61080D02*
X675968Y61055D01*
G01X675918D02*
X675910Y61080D01*
G01X677559Y55906D02*
Y62205D01*
G01Y55906D02*
Y62205D01*
G01X677362Y55906D02*
Y57480D01*
G01Y62205D02*
Y60630D01*
G01X676640Y61147D02*
Y60753D01*
G01X676591D02*
Y61080D01*
G01X676542Y61021D02*
Y61088D01*
G01X676476Y61147D02*
Y60753D01*
G01X676427Y60812D02*
Y61147D01*
G01X676197Y61097D02*
Y60753D01*
G01X676148D02*
Y61147D01*
G01X676082D02*
Y60753D01*
G01X676033D02*
Y61147D01*
G01X675968Y61055D02*
Y61021D01*
G01X675918Y61030D02*
Y61055D01*
G01X675713Y61105D02*
Y60979D01*
G01Y60929D02*
Y60753D01*
G01X675664D02*
Y61147D01*
G01X675000Y60630D02*
Y62205D01*
G01Y57480D02*
Y55906D01*
G01X674212D02*
Y57480D01*
G01Y62205D02*
Y60630D01*
G01X671850D02*
Y62205D01*
G01Y57480D02*
Y55906D01*
G01X671653D02*
Y62205D01*
G01D02*
Y55906D01*
G01X676402Y60753D02*
X676197Y61097D01*
G01X676222Y61147D02*
X676427Y60812D01*
G01X675968Y61021D02*
X675959Y60996D01*
G01X675910Y61004D02*
X675918Y61030D01*
G01X675935Y61113D02*
X675959Y61080D01*
G01X675910D02*
X675894Y61097D01*
G01X675959Y60996D02*
X675935Y60963D01*
G01X675902Y61139D02*
X675935Y61113D01*
G01X675894Y60988D02*
X675910Y61004D01*
G01X676591Y61080D02*
X676542Y61021D01*
G01Y61088D02*
X676591Y61147D01*
G01X675935Y60963D02*
X675902Y60937D01*
G01X675894Y61097D02*
X675869Y61105D01*
G01X675861Y61147D02*
X675902Y61139D01*
G01X675869Y60979D02*
X675894Y60988D01*
G01X675000Y62205D02*
X677362D01*
G01X671850D02*
X674212D01*
G01X672441D02*
X671653D01*
G01X672441D02*
X671653D01*
G01X675590D02*
X673622D01*
G01X675590D02*
X673622D01*
G01X677559D02*
X676772D01*
G01X677559D02*
X676772D01*
G01X677559Y61221D02*
X671653D01*
G01X676591Y61147D02*
X676640D01*
G01X676427D02*
X676476D01*
G01X676148D02*
X676222D01*
G01X676033D02*
X676082D01*
G01X675664D02*
X675861D01*
G01X675869Y61105D02*
X675713D01*
G01X671653Y61024D02*
X677559D01*
G01X675713Y60979D02*
X675869D01*
G01X675861Y60929D02*
X675713D01*
G01X676640Y60753D02*
X676591D01*
G01X676476D02*
X676402D01*
G01X676197D02*
X676148D01*
G01X676082D02*
X676033D01*
G01X675713D02*
X675664D01*
G01X674212Y60630D02*
X671850D01*
G01X677362D02*
X675000D01*
G01X674212Y57480D02*
X671850D01*
G01X677362D02*
X675000D01*
G01X671653Y57087D02*
X677559D01*
G01Y56890D02*
X671653D01*
G01X675000Y55906D02*
X677362D01*
G01X676772D02*
X677559D01*
G01X676772D02*
X677559D01*
G01X673622D02*
X675590D01*
G01X673622D02*
X675590D01*
G01X671850D02*
X674212D01*
G01X671653D02*
X672441D01*
G01X671653D02*
X672441D01*
G01X675902Y60937D02*
X675861Y60929D01*
G01X686417Y67717D02*
X662795D01*
G01X690354Y63780D02*
G03X686417Y67717I-3937J0D01*
G01X690354Y43307D02*
Y63780D01*
G01Y43307D02*
G03X694291Y39370I3937J0D01*
G01X724409D02*
X694291D01*
G01X686319Y154331D02*
G03X674902I-5708J0D01*
G01D02*
G03X686319I5708J0D01*
G01X717106D02*
G03X707106I-5000J0D01*
G01D02*
G03X717106I5000J0D01*
G01X701969Y174016D02*
G03Y181890I0J3937D01*
G01Y206300D02*
G03Y214174I0J3937D01*
G01X698228Y206300D02*
X701969D01*
G01X698228Y181890D02*
Y206300D01*
G01X701969Y181890D02*
X698228D01*
G01X686417Y202363D02*
X662795D01*
G01X690354Y198426D02*
G03X686417Y202363I-3937J0D01*
G01X690354Y177953D02*
Y198426D01*
G01Y177953D02*
G03X694291Y174016I3937J0D01*
G01X724409D02*
X694291D01*
G01X701969Y308662D02*
G03Y316536I0J3937D01*
G01X686319Y288977D02*
G03X674902I-5708J0D01*
G01D02*
G03X686319I5708J0D01*
G01X717106D02*
G03X707106I-5000J0D01*
G01D02*
G03X717106I5000J0D01*
G01X690354Y312599D02*
G03X694291Y308662I3937J0D01*
G01X724409D02*
X694291D01*
G01X701969Y340946D02*
G03Y348820I0J3937D01*
G01X698228Y340946D02*
X701969D01*
G01X698228Y316536D02*
Y340946D01*
G01X701969Y316536D02*
X698228D01*
G01X686417Y337009D02*
X662795D01*
G01X690354Y333072D02*
G03X686417Y337009I-3937J0D01*
G01X690354Y312599D02*
Y333072D01*
G01X701969Y443308D02*
G03Y451182I0J3937D01*
G01X698228D02*
Y475592D01*
G01X701969Y451182D02*
X698228D01*
G01X686319Y423623D02*
G03X674902I-5708J0D01*
G01D02*
G03X686319I5708J0D01*
G01X717106D02*
G03X707106I-5000J0D01*
G01D02*
G03X717106I5000J0D01*
G01X690354Y447245D02*
Y467718D01*
G01Y447245D02*
G03X694291Y443308I3937J0D01*
G01X724409D02*
X694291D01*
G01X701969Y475592D02*
G03Y483466I0J3937D01*
G01X698228Y475592D02*
X701969D01*
G01X686417Y471655D02*
X662795D01*
G01X690354Y467718D02*
G03X686417Y471655I-3937J0D01*
G01X701969Y577954D02*
G03Y585828I0J3937D01*
G01X698228D02*
Y610238D01*
G01X701969Y585828D02*
X698228D01*
G01X686319Y558269D02*
G03X674902I-5708J0D01*
G01D02*
G03X686319I5708J0D01*
G01X717106D02*
G03X707106I-5000J0D01*
G01D02*
G03X717106I5000J0D01*
G01X690354Y581891D02*
Y602364D01*
G01Y581891D02*
G03X694291Y577954I3937J0D01*
G01X724409D02*
X694291D01*
G01X701969Y610238D02*
G03Y618112I0J3937D01*
G01X698228Y610238D02*
X701969D01*
G01X686417Y606301D02*
X662795D01*
G01X690354Y602364D02*
G03X686417Y606301I-3937J0D01*
G01X674902Y692915D02*
G03X686319I5708J0D01*
G01X707106D02*
G03X717106I5000J0D01*
G01X701969Y712600D02*
G03Y720474I0J3937D01*
G01X698228D02*
Y744884D01*
G01X701969Y720474D02*
X698228D01*
G01X686319Y692915D02*
G03X674902I-5708J0D01*
G01X717106D02*
G03X707106I-5000J0D01*
G01X690354Y737010D02*
G03X686417Y740947I-3937J0D01*
G01X690354Y716537D02*
Y737010D01*
G01Y716538D02*
G03X694291Y712601I3937J0D01*
G01X724409Y712600D02*
X694291D01*
G01X701969Y744884D02*
G03Y752758I0J3937D01*
G01X698228Y744884D02*
X701969D01*
G01X686417Y740947D02*
X662795D01*
G01X686319Y827561D02*
G03X674902I-5708J0D01*
G01D02*
G03X686319I5708J0D01*
G01X717106D02*
G03X707106I-5000J0D01*
G01D02*
G03X717106I5000J0D01*
G01X701969Y847246D02*
G03Y855120I0J3937D01*
G01Y879530D02*
G03Y887404I0J3937D01*
G01X698228Y879530D02*
X701969D01*
G01X698228Y855120D02*
Y879530D01*
G01X701969Y855120D02*
X698228D01*
G01X686417Y875593D02*
X662795D01*
G01X690354Y871656D02*
G03X686417Y875593I-3937J0D01*
G01X690354Y851183D02*
Y871656D01*
G01Y851184D02*
G03X694291Y847247I3937J0D01*
G01X724409Y847246D02*
X694291D01*
G01X736220Y0D02*
G03X740157Y-3937I3937J0D01*
G01X736220Y5118D02*
Y0D01*
G01X740157Y-3937D02*
X793111D01*
G01X736220Y5118D02*
G03X728346I-3937J0D01*
G01X724409Y-3937D02*
G03X728346Y0I0J3937D01*
G01D02*
Y35433D01*
G01X720079Y71654D02*
X723820D01*
G01X720079Y47244D02*
G03Y39370I0J-3937D01*
G01Y79528D02*
G03Y71654I0J-3937D01*
G01X723820D02*
Y47244D01*
G01D02*
X720079D01*
G01X740157Y43307D02*
G03X736220Y39370I0J-3937D01*
G01X740157Y43307D02*
X759253D01*
G01X735631Y51181D02*
X759253D01*
G01X731694Y55118D02*
G03X735631Y51181I3937J0D01*
G01X731694Y75591D02*
Y55118D01*
G01X728346Y30315D02*
G03X736220I3937J0D01*
G01X728346Y35433D02*
G03X724409Y39370I-3937J0D01*
G01X736220Y30315D02*
Y39370D01*
G01X747540Y99213D02*
G03X758957I5708J0D01*
G01D02*
G03X747540I-5709J0D01*
G01X731694Y75591D02*
G03X727757Y79528I-3937J0D01*
G01X758378Y115119D02*
G03Y111103I0J-2008D01*
G01X752078Y117011D02*
X764678D01*
G01X752078Y109211D02*
Y117011D01*
G01X764678Y109211D02*
X752078D01*
G01X750978Y118111D02*
X765778D01*
G01X750978Y108111D02*
Y118111D01*
G01X765778Y108111D02*
X750978D01*
G01X736220Y134646D02*
G03X740157Y130709I3937J0D01*
G01X771064D02*
X740157D01*
G01X736220Y139764D02*
Y134646D01*
G01X728346Y164961D02*
G03X736220I3937J0D01*
G01Y139764D02*
G03X728346I-3937J0D01*
G01X724409Y130709D02*
G03X728346Y134646I0J3937D01*
G01X736220Y164961D02*
Y174016D01*
G01X728346Y134646D02*
Y170079D01*
G01X720079Y181890D02*
G03Y174016I0J-3937D01*
G01Y214174D02*
G03Y206300I0J-3937D01*
G01X723820D02*
Y181890D01*
G01X720079Y206300D02*
X723820D01*
G01Y181890D02*
X720079D01*
G01X740157Y177953D02*
G03X736220Y174016I0J-3937D01*
G01X740157Y177953D02*
X759253D01*
G01X735631Y185827D02*
X759253D01*
G01X731694Y189764D02*
G03X735631Y185827I3937J0D01*
G01X731694Y210237D02*
Y189764D01*
G01Y210237D02*
G03X727757Y214174I-3937J0D01*
G01X728346Y170079D02*
G03X724409Y174016I-3937J0D01*
G01X747540Y233859D02*
G03X758957I5708J0D01*
G01D02*
G03X747540I-5709J0D01*
G01X758378Y249765D02*
G03Y245749I0J-2008D01*
G01X752078Y251657D02*
X764678D01*
G01X752078Y243857D02*
Y251657D01*
G01X764678Y243857D02*
X752078D01*
G01X750978Y252757D02*
X765778D01*
G01X750978Y242757D02*
Y252757D01*
G01X765778Y242757D02*
X750978D01*
G01X720079Y316536D02*
G03Y308662I0J-3937D01*
G01X736220Y269292D02*
G03X740157Y265355I3937J0D01*
G01Y312599D02*
G03X736220Y308662I0J-3937D01*
G01X771064Y265355D02*
X740157D01*
G01X736220Y274410D02*
Y269292D01*
G01X728346Y299607D02*
G03X736220I3937J0D01*
G01Y274410D02*
G03X728346I-3937J0D01*
G01X736220Y299607D02*
Y308662D01*
G01X724409Y265355D02*
G03X728346Y269292I0J3937D01*
G01Y304725D02*
G03X724409Y308662I-3937J0D01*
G01X728346Y269292D02*
Y304725D01*
G01X720079Y348820D02*
G03Y340946I0J-3937D01*
G01X723820D02*
Y316536D01*
G01X720079Y340946D02*
X723820D01*
G01Y316536D02*
X720079D01*
G01X740157Y312599D02*
X759253D01*
G01X735631Y320473D02*
X759253D01*
G01X731694Y324410D02*
G03X735631Y320473I3937J0D01*
G01X731694Y344883D02*
Y324410D01*
G01Y344883D02*
G03X727757Y348820I-3937J0D01*
G01X736220Y403938D02*
G03X740157Y400001I3937J0D01*
G01X771064D02*
X740157D01*
G01X736220Y409056D02*
Y403938D01*
G01X724409Y400001D02*
G03X728346Y403938I0J3937D01*
G01D02*
Y439371D01*
G01X747540Y368505D02*
G03X758957I5708J0D01*
G01D02*
G03X747540I-5709J0D01*
G01X758378Y384411D02*
G03Y380395I0J-2008D01*
G01X752078Y386303D02*
X764678D01*
G01X752078Y378503D02*
Y386303D01*
G01X764678Y378503D02*
X752078D01*
G01X750978Y387403D02*
X765778D01*
G01X750978Y377403D02*
Y387403D01*
G01X765778Y377403D02*
X750978D01*
G01X720079Y451182D02*
G03Y443308I0J-3937D01*
G01X723820Y475592D02*
Y451182D01*
G01D02*
X720079D01*
G01X740157Y447245D02*
G03X736220Y443308I0J-3937D01*
G01X740157Y447245D02*
X759253D01*
G01X728346Y434253D02*
G03X736220I3937J0D01*
G01Y409056D02*
G03X728346I-3937J0D01*
G01X736220Y434253D02*
Y443308D01*
G01X728346Y439371D02*
G03X724409Y443308I-3937J0D01*
G01X720079Y483466D02*
G03Y475592I0J-3937D01*
G01D02*
X723820D01*
G01X747540Y503151D02*
G03X758957I5708J0D01*
G01X735631Y455119D02*
X759253D01*
G01X731694Y459056D02*
G03X735631Y455119I3937J0D01*
G01X731694Y479529D02*
Y459056D01*
G01Y479529D02*
G03X727757Y483466I-3937J0D01*
G01X736220Y538584D02*
G03X740157Y534647I3937J0D01*
G01X771064D02*
X740157D01*
G01X736220Y543702D02*
Y538584D01*
G01Y543702D02*
G03X728346I-3937J0D01*
G01X724409Y534647D02*
G03X728346Y538584I0J3937D01*
G01D02*
Y574017D01*
G01X758957Y503151D02*
G03X747540I-5709J0D01*
G01X758378Y519057D02*
G03Y515041I0J-2008D01*
G01X752078Y520949D02*
X764678D01*
G01X752078Y513149D02*
Y520949D01*
G01X764678Y513149D02*
X752078D01*
G01X750978Y522049D02*
X765778D01*
G01X750978Y512049D02*
Y522049D01*
G01X765778Y512049D02*
X750978D01*
G01X720079Y585828D02*
G03Y577954I0J-3937D01*
G01X723820Y610238D02*
Y585828D01*
G01D02*
X720079D01*
G01X740157Y581891D02*
G03X736220Y577954I0J-3937D01*
G01X740157Y581891D02*
X759253D01*
G01X728346Y568899D02*
G03X736220I3937J0D01*
G01D02*
Y577954D01*
G01X735631Y589765D02*
X759253D01*
G01X731694Y593702D02*
G03X735631Y589765I3937J0D01*
G01X731694Y614175D02*
Y593702D01*
G01X728346Y574017D02*
G03X724409Y577954I-3937J0D01*
G01X720079Y618112D02*
G03Y610238I0J-3937D01*
G01D02*
X723820D01*
G01X747540Y637797D02*
G03X758957I5708J0D01*
G01D02*
G03X747540I-5709J0D01*
G01X731694Y614175D02*
G03X727757Y618112I-3937J0D01*
G01X736220Y673230D02*
G03X740157Y669293I3937J0D01*
G01X771064D02*
X740157D01*
G01X736220Y678348D02*
Y673230D01*
G01Y678348D02*
G03X728346I-3937J0D01*
G01X724409Y669293D02*
G03X728346Y673230I0J3937D01*
G01D02*
Y708663D01*
G01X758378Y653703D02*
G03Y649687I0J-2008D01*
G01X752078Y655595D02*
X764678D01*
G01X752078Y647795D02*
Y655595D01*
G01X764678Y647795D02*
X752078D01*
G01X750978Y656695D02*
X765778D01*
G01X750978Y646695D02*
Y656695D01*
G01X765778Y646695D02*
X750978D01*
G01X720079Y720474D02*
G03Y712600I0J-3937D01*
G01X723820Y744884D02*
Y720474D01*
G01D02*
X720079D01*
G01X740157Y716537D02*
G03X736220Y712600I0J-3937D01*
G01X740157Y716537D02*
X759253D01*
G01X728346Y703545D02*
G03X736220I3937J0D01*
G01D02*
Y712600D01*
G01X735631Y724411D02*
X759253D01*
G01X731694Y728348D02*
G03X735631Y724411I3937J0D01*
G01X731694Y748821D02*
Y728348D01*
G01X728346Y708664D02*
G03X724409Y712601I-3937J0D01*
G01X720079Y752758D02*
G03Y744884I0J-3937D01*
G01D02*
X723820D01*
G01X747540Y772443D02*
G03X758957I5708J0D01*
G01D02*
G03X747540I-5709J0D01*
G01X731694Y748821D02*
G03X727757Y752758I-3937J0D01*
G01X758378Y788349D02*
G03Y784333I0J-2008D01*
G01X752078Y782441D02*
Y790241D01*
G01X764678Y782441D02*
X752078D01*
G01X750978Y781341D02*
Y791341D01*
G01X765778Y781341D02*
X750978D01*
G01X755130Y826310D02*
G03I-4000J0D01*
G01X753130D02*
G03I-2000J0D01*
G01X736220Y807876D02*
G03X740157Y803939I3937J0D01*
G01X771064D02*
X740157D01*
G01X736220Y812995D02*
Y807876D01*
G01X728346Y838191D02*
G03X736220I3937J0D01*
G01Y812995D02*
G03X728346I-3937J0D01*
G01X724409Y803939D02*
G03X728346Y807876I0J3937D01*
G01D02*
Y843309D01*
G01X752078Y790241D02*
X764678D01*
G01X750978Y791341D02*
X765778D01*
G01X720079Y855120D02*
G03Y847246I0J-3937D01*
G01Y887404D02*
G03Y879530I0J-3937D01*
G01X723820D02*
Y855120D01*
G01X720079Y879530D02*
X723820D01*
G01Y855120D02*
X720079D01*
G01X728346Y843556D02*
Y964887D01*
G01X740157Y851183D02*
G03X736220Y847246I0J-3937D01*
G01X740157Y851183D02*
X759253D01*
G01X736220Y838191D02*
Y847246D01*
G01X735631Y859057D02*
X759253D01*
G01X731694Y862994D02*
G03X735631Y859057I3937J0D01*
G01X731694Y883467D02*
Y862994D01*
G01X728346Y843310D02*
G03X724409Y847247I-3937J0D01*
G01X747540Y907089D02*
G03X758957I5708J0D01*
G01D02*
G03X747540I-5709J0D01*
G01X731694Y883467D02*
G03X727757Y887404I-3937J0D01*
G01X758378Y922995D02*
G03Y918979I0J-2008D01*
G01X752078Y924887D02*
X764678D01*
G01X752078Y917087D02*
Y924887D01*
G01X764678Y917087D02*
X752078D01*
G01X750978Y925987D02*
X765778D01*
G01X750978Y915987D02*
Y925987D01*
G01X765778Y915987D02*
X750978D01*
G01X793111Y-3937D02*
G03X800985Y3937I0J7874D01*
G01Y67717D02*
Y3937D01*
G01X789036Y19685D02*
G03I-4291J0D01*
G01X769026Y19107D02*
G03I-4000J0D01*
G01X767026D02*
G03I-2000J0D01*
G01X765026Y23107D02*
X780241Y38322D01*
G01X772096Y26642D02*
X765026Y23107D01*
G01D02*
X768561Y30177D01*
G01X800985Y67717D02*
G03X797048Y71654I-3937J0D01*
G01X796261D02*
X797048D01*
G01X771064Y55118D02*
Y71654D01*
G01X763190Y55118D02*
Y75591D01*
G01X759253Y43307D02*
G03X771064Y55118I0J11811D01*
G01X759253Y51181D02*
G03X763190Y55118I0J3937D01*
G01X796261Y79528D02*
G03Y71654I0J-3937D01*
G01X771064D02*
G03Y79528I0J3937D01*
G01X780241Y38322D02*
X816441D01*
G01X768561Y30177D02*
X772096Y26642D01*
G01X779706Y99213D02*
G03X789784I5039J0D01*
G01D02*
G03X779706I-5039J0D01*
G01X800985Y118898D02*
G03X797048Y122835I-3937J0D01*
G01X800985Y83465D02*
Y118898D01*
G01X797048Y79528D02*
G03X800985Y83465I0J3937D01*
G01X767127Y79528D02*
X797048D01*
G01X767127D02*
G03X763190Y75591I0J-3937D01*
G01X758378Y111103D02*
G03Y115119I0J2008D01*
G01X764678Y117011D02*
Y109211D01*
G01X765778Y118111D02*
Y108111D01*
G01X797048Y130709D02*
G03X800985Y134646I0J3937D01*
G01X796261Y130709D02*
X797048D01*
G01X800985Y202363D02*
Y134646D01*
G01X789036Y154331D02*
G03I-4291J0D01*
G01X771064Y122835D02*
G03Y130709I0J3937D01*
G01X796261D02*
G03Y122835I0J-3937D01*
G01X800985Y202363D02*
G03X797048Y206300I-3937J0D01*
G01Y214174D02*
G03X800985Y218111I0J3937D01*
G01X796261Y206300D02*
X797048D01*
G01X767127Y214174D02*
X797048D01*
G01X767127D02*
G03X763190Y210237I0J-3937D01*
G01X771064Y189764D02*
Y206300D01*
G01X763190Y189764D02*
Y210237D01*
G01X759253Y177953D02*
G03X771064Y189764I0J11811D01*
G01X759253Y185827D02*
G03X763190Y189764I0J3937D01*
G01X796261Y214174D02*
G03Y206300I0J-3937D01*
G01X771064D02*
G03Y214174I0J3937D01*
G01Y257481D02*
G03Y265355I0J3937D01*
G01X796261D02*
G03Y257481I0J-3937D01*
G01X779706Y233859D02*
G03X789784I5039J0D01*
G01D02*
G03X779706I-5039J0D01*
G01X800985Y253544D02*
G03X797048Y257481I-3937J0D01*
G01X800985Y218111D02*
Y253544D01*
G01X758378Y245749D02*
G03Y249765I0J2008D01*
G01X764678Y251657D02*
Y243857D01*
G01X765778Y252757D02*
Y242757D01*
G01X797048Y265355D02*
G03X800985Y269292I0J3937D01*
G01X796261Y265355D02*
X797048D01*
G01X800985Y337009D02*
Y269292D01*
G01X789036Y288977D02*
G03I-4291J0D01*
G01X800985Y337009D02*
G03X797048Y340946I-3937J0D01*
G01X796261D02*
X797048D01*
G01X771064Y324410D02*
Y340946D01*
G01X759253Y312599D02*
G03X771064Y324410I0J11811D01*
G01X796261Y348820D02*
G03Y340946I0J-3937D01*
G01X771064D02*
G03Y348820I0J3937D01*
G01X800985Y352757D02*
Y388190D01*
G01X797048Y348820D02*
G03X800985Y352757I0J3937D01*
G01X767127Y348820D02*
X797048D01*
G01X767127D02*
G03X763190Y344883I0J-3937D01*
G01Y324410D02*
Y344883D01*
G01X759253Y320473D02*
G03X763190Y324410I0J3937D01*
G01X797048Y400001D02*
G03X800985Y403938I0J3937D01*
G01X796261Y400001D02*
X797048D01*
G01X800985Y471655D02*
Y403938D01*
G01X771064Y392127D02*
G03Y400001I0J3937D01*
G01X796261D02*
G03Y392127I0J-3937D01*
G01X779706Y368505D02*
G03X789784I5039J0D01*
G01D02*
G03X779706I-5039J0D01*
G01X800985Y388190D02*
G03X797048Y392127I-3937J0D01*
G01X758378Y380395D02*
G03Y384411I0J2008D01*
G01X764678Y386303D02*
Y378503D01*
G01X765778Y387403D02*
Y377403D01*
G01X759253Y447246D02*
G03X771064Y459057I0J11811D01*
G01X789036Y423623D02*
G03I-4291J0D01*
G01X800985Y471655D02*
G03X797048Y475592I-3937J0D01*
G01X796261D02*
X797048D01*
G01X771064Y459056D02*
Y475592D01*
G01X796261Y483466D02*
G03Y475592I0J-3937D01*
G01X771064D02*
G03Y483466I0J3937D01*
G01X779706Y503151D02*
G03X789784I5039J0D01*
G01X800985Y487403D02*
Y522836D01*
G01X797048Y483466D02*
G03X800985Y487403I0J3937D01*
G01X767127Y483466D02*
X797048D01*
G01X767127D02*
G03X763190Y479529I0J-3937D01*
G01Y459056D02*
Y479529D01*
G01X759253Y455120D02*
G03X763190Y459057I0J3937D01*
G01X797048Y534647D02*
G03X800985Y538584I0J3937D01*
G01X796261Y534647D02*
X797048D01*
G01X800985Y606301D02*
Y538584D01*
G01X771064Y526773D02*
G03Y534647I0J3937D01*
G01X796261D02*
G03Y526773I0J-3937D01*
G01X789784Y503151D02*
G03X779706I-5039J0D01*
G01X800985Y522836D02*
G03X797048Y526773I-3937J0D01*
G01X758378Y515041D02*
G03Y519057I0J2008D01*
G01X764678Y520949D02*
Y513149D01*
G01X765778Y522049D02*
Y512049D01*
G01X771064Y593702D02*
Y610238D01*
G01X759253Y581892D02*
G03X771064Y593703I0J11811D01*
G01X789036Y558269D02*
G03I-4291J0D01*
G01X763190Y593702D02*
Y614175D01*
G01X759253Y589766D02*
G03X763190Y593703I0J3937D01*
G01X800985Y606301D02*
G03X797048Y610238I-3937J0D01*
G01X796261D02*
X797048D01*
G01X796261Y618112D02*
G03Y610238I0J-3937D01*
G01X771064D02*
G03Y618112I0J3937D01*
G01X779706Y637797D02*
G03X789784I5039J0D01*
G01D02*
G03X779706I-5039J0D01*
G01X800985Y622049D02*
Y657482D01*
G01X797048Y618112D02*
G03X800985Y622049I0J3937D01*
G01X767127Y618112D02*
X797048D01*
G01X767127D02*
G03X763190Y614175I0J-3937D01*
G01X797048Y669293D02*
G03X800985Y673230I0J3937D01*
G01X796261Y669293D02*
X797048D01*
G01X800985Y740947D02*
Y673230D01*
G01X789036Y692915D02*
G03I-4291J0D01*
G01X771064Y661419D02*
G03Y669293I0J3937D01*
G01X796261D02*
G03Y661419I0J-3937D01*
G01X800985Y657482D02*
G03X797048Y661419I-3937J0D01*
G01X758378Y649687D02*
G03Y653703I0J2008D01*
G01X764678Y655595D02*
Y647795D01*
G01X765778Y656695D02*
Y646695D01*
G01X771064Y728348D02*
Y744884D01*
G01X759253Y716538D02*
G03X771064Y728349I0J11811D01*
G01X763190Y728348D02*
Y748821D01*
G01X759253Y724412D02*
G03X763190Y728349I0J3937D01*
G01X800985Y740947D02*
G03X797048Y744884I-3937J0D01*
G01X796261D02*
X797048D01*
G01X796261Y752758D02*
G03Y744884I0J-3937D01*
G01X771064D02*
G03Y752758I0J3937D01*
G01X779706Y772443D02*
G03X789784I5039J0D01*
G01D02*
G03X779706I-5039J0D01*
G01X800985Y756695D02*
Y792128D01*
G01X797048Y752758D02*
G03X800985Y756695I0J3937D01*
G01X767127Y752758D02*
X797048D01*
G01X767127D02*
G03X763190Y748821I0J-3937D01*
G01X758378Y784333D02*
G03Y788349I0J2008D01*
G01X764678Y790241D02*
Y782441D01*
G01X765778Y791341D02*
Y781341D01*
G01X800985Y855100D02*
Y807876D01*
G01X797048Y803939D02*
G03X800985Y807876I0J3937D01*
G01X796261Y803939D02*
X797048D01*
G01X789036Y827561D02*
G03I-4291J0D01*
G01X771064Y796065D02*
G03Y803939I0J3937D01*
G01X796261D02*
G03Y796065I0J-3937D01*
G01X800985Y792128D02*
G03X797048Y796065I-3937J0D01*
G01X800985Y859037D02*
Y857493D01*
G01Y859037D02*
Y861072D01*
G01X799585Y859037D02*
X802385D01*
G01X800985Y862974D02*
G03Y855100I0J-3937D01*
G01Y875593D02*
G03X797048Y879530I-3937J0D01*
G01X800985Y875593D02*
Y862974D01*
G01X796261Y879530D02*
X797048D01*
G01X771064Y862994D02*
Y879530D01*
G01X759253Y851184D02*
G03X771064Y862995I0J11811D01*
G01X796261Y887404D02*
G03Y879530I0J-3937D01*
G01X771064D02*
G03Y887404I0J3937D01*
G01X763190Y862994D02*
Y883467D01*
G01X759253Y859058D02*
G03X763190Y862995I0J3937D01*
G01X800985Y927020D02*
Y964887D01*
G01X779706Y907089D02*
G03X789784I5039J0D01*
G01D02*
G03X779706I-5039J0D01*
G01X800985Y926774D02*
G03X797048Y930711I-3937J0D01*
G01X800985Y891341D02*
Y926774D01*
G01X797048Y887404D02*
G03X800985Y891341I0J3937D01*
G01X767127Y887404D02*
X797048D01*
G01X767127D02*
G03X763190Y883467I0J-3937D01*
G01X758378Y918979D02*
G03Y922995I0J2008D01*
G01X764678Y924887D02*
Y917087D01*
G01X765778Y925987D02*
Y915987D01*
G01X845660Y-618663D02*
Y-637600D01*
G01Y1559093D02*
Y1540156D01*
G01X1065329Y-618663D02*
Y-637600D01*
G01Y1559093D02*
Y1540156D01*
G01X1284999Y-618663D02*
Y-637600D01*
G01X1453954Y251258D02*
X1323744D01*
G01X1284999Y1559093D02*
Y1540156D01*
G01X1334354Y255589D02*
X1338739D01*
G01X1337765Y262085D02*
X1334354Y255589D01*
G01X1337765Y253423D02*
Y262085D01*
G01X1348718Y255589D02*
X1347996Y257754D01*
G01X1350162Y254145D02*
X1348718Y255589D01*
G01X1352327Y253423D02*
X1350162Y254145D01*
G01X1354492D02*
X1352327Y253423D01*
G01X1355936Y255589D02*
X1354492Y254145D01*
G01X1356658Y257754D02*
X1355936Y255589D01*
G01Y259919D02*
X1356658Y257754D01*
G01X1354492Y261363D02*
X1355936Y259919D01*
G01X1352327Y262085D02*
X1354492Y261363D01*
G01X1350162D02*
X1352327Y262085D01*
G01X1348718Y259919D02*
X1350162Y261363D01*
G01X1347996Y257754D02*
X1348718Y259919D01*
G01X1364904Y258476D02*
X1362955Y257032D01*
G01X1365391Y259198D02*
X1364904Y258476D01*
G01X1365391Y260641D02*
Y259198D01*
G01X1364904Y261363D02*
X1365391Y260641D01*
G01X1363930Y262085D02*
X1364904Y261363D01*
G01X1362955Y262085D02*
X1363930D01*
G01X1361981Y261363D02*
X1362955Y262085D01*
G01X1361494Y260641D02*
X1361981Y261363D01*
G01X1361494Y253423D02*
X1365391D01*
G01X1361981Y255589D02*
X1361494Y253423D01*
G01X1362955Y257032D02*
X1361981Y255589D01*
G01X1370751Y254145D02*
X1371238Y253423D01*
G01X1370751D02*
Y254145D01*
G01X1371238Y253423D02*
X1370751D01*
G01X1377571Y254145D02*
X1377084Y254867D01*
G01X1378546Y253423D02*
X1377571Y254145D01*
G01Y258476D02*
X1378546Y259198D01*
G01X1378059Y262085D02*
X1377571Y258476D01*
G01X1342637Y257754D02*
X1345560D01*
G01X1348718Y251258D02*
X1355936Y264250D01*
G01X1376885Y683570D02*
X1377859Y682848D01*
G01X1375911D02*
X1376885Y683570D01*
G01X1375423Y682127D02*
X1375911Y682848D01*
G01X1374936Y680683D02*
X1375423Y682127D01*
G01X1374936Y677796D02*
Y680683D01*
G01X1375423Y676352D02*
X1374936Y677796D01*
G01X1375911Y675630D02*
X1375423Y676352D01*
G01X1376885Y674909D02*
X1375911Y675630D01*
G01X1377859D02*
X1376885Y674909D01*
G01Y679961D02*
X1378347Y679239D01*
G01X1375423D02*
X1376885Y679961D01*
G01X1374936Y677796D02*
X1375423Y679239D01*
G01X1369670Y652008D02*
X1368696Y651287D01*
G01X1370158Y652730D02*
X1369670Y652008D01*
G01X1370645Y654174D02*
X1370158Y652730D01*
G01X1370645Y657061D02*
Y654174D01*
G01X1370158Y658505D02*
X1370645Y657061D01*
G01X1369670Y659226D02*
X1370158Y658505D01*
G01X1368696Y659948D02*
X1369670Y659226D01*
G01X1367722D02*
X1368696Y659948D01*
G01X1367234Y658505D02*
X1367722Y659226D01*
G01X1366747Y657061D02*
X1367234Y658505D01*
G01X1366747Y654174D02*
Y657061D01*
G01X1367234Y652730D02*
X1366747Y654174D01*
G01X1367722Y652008D02*
X1367234Y652730D01*
G01X1368696Y651287D02*
X1367722Y652008D01*
G01X1377466D02*
X1376491Y651287D01*
G01X1377953Y652730D02*
X1377466Y652008D01*
G01Y659226D02*
X1377953Y658505D01*
G01X1376491Y659948D02*
X1377466Y659226D01*
G01X1375517D02*
X1376491Y659948D01*
G01X1375030Y658505D02*
X1375517Y659226D01*
G01X1374542Y657061D02*
X1375030Y658505D01*
G01X1374542Y654174D02*
Y657061D01*
G01X1375030Y652730D02*
X1374542Y654174D01*
G01X1375517Y652008D02*
X1375030Y652730D01*
G01X1376491Y651287D02*
X1375517Y652008D01*
G01X1360414D02*
X1360901Y651287D01*
G01X1360414D02*
Y652008D01*
G01X1360901Y651287D02*
X1360414D01*
G01X1353105Y659948D02*
Y651287D01*
G01X1410701Y257754D02*
X1408265D01*
G01X1411676Y258476D02*
X1410701Y257754D01*
G01X1412163Y259198D02*
X1411676Y258476D01*
G01X1412163Y260641D02*
Y259198D01*
G01X1411676Y261363D02*
X1412163Y260641D01*
G01X1410701Y262085D02*
X1411676Y261363D01*
G01X1408265Y262085D02*
X1410701D01*
G01X1408265Y253423D02*
Y262085D01*
G01X1394136Y254867D02*
X1395111Y253423D01*
G01X1393649Y257032D02*
X1394136Y254867D01*
G01X1393649Y258476D02*
Y257032D01*
G01X1394136Y260641D02*
X1393649Y258476D01*
G01X1395111Y262085D02*
X1394136Y260641D01*
G01X1401932Y254867D02*
X1402906Y253423D01*
G01X1401444Y257032D02*
X1401932Y254867D01*
G01X1401444Y258476D02*
Y257032D01*
G01X1401932Y260641D02*
X1401444Y258476D01*
G01X1402906Y262085D02*
X1401932Y260641D01*
G01X1385367Y254145D02*
X1384879Y254867D01*
G01X1386341Y253423D02*
X1385367Y254145D01*
G01X1387315Y253423D02*
X1386341D01*
G01X1388290Y254145D02*
X1387315Y253423D01*
G01X1388777Y254867D02*
X1388290Y254145D01*
G01X1389264Y256310D02*
X1388777Y254867D01*
G01Y257754D02*
X1389264Y256310D01*
G01X1388290Y258476D02*
X1388777Y257754D01*
G01X1387315Y259198D02*
X1388290Y258476D01*
G01X1386341Y259198D02*
X1387315D01*
G01X1385367Y258476D02*
X1386341Y259198D01*
G01X1385854Y262085D02*
X1385367Y258476D01*
G01X1388777Y262085D02*
X1385854D01*
G01X1379520Y253423D02*
X1378546D01*
G01X1380495Y254145D02*
X1379520Y253423D01*
G01X1380982Y254867D02*
X1380495Y254145D01*
G01X1381469Y256310D02*
X1380982Y254867D01*
G01Y257754D02*
X1381469Y256310D01*
G01X1380495Y258476D02*
X1380982Y257754D01*
G01X1379520Y259198D02*
X1380495Y258476D01*
G01X1378546Y259198D02*
X1379520D01*
G01X1380982Y262085D02*
X1378059D01*
G01X1415573D02*
X1420445D01*
G01X1423856Y257754D02*
X1427753D01*
G01X1423856Y262085D02*
Y253423D01*
G01X1418009Y262085D02*
Y253423D01*
G01X1459129Y653058D02*
X1424090D01*
G01X1466413Y672743D02*
X1424090D01*
G01X1459129Y649121D02*
X1384720D01*
G01X1377859Y682848D02*
X1378347Y682127D01*
G01Y676352D02*
X1377859Y675630D01*
G01X1378834Y677796D02*
X1378347Y676352D01*
G01Y679239D02*
X1378834Y677796D01*
G01X1378440Y654174D02*
X1377953Y652730D01*
G01X1378440Y657061D02*
Y654174D01*
G01X1377953Y658505D02*
X1378440Y657061D01*
G01X1393450Y655946D02*
X1392476Y655224D01*
G01X1393937Y656667D02*
X1393450Y655946D01*
G01X1394424Y658111D02*
X1393937Y656667D01*
G01X1394424Y660998D02*
Y658111D01*
G01X1393937Y662442D02*
X1394424Y660998D01*
G01X1393450Y663163D02*
X1393937Y662442D01*
G01X1392476Y663885D02*
X1393450Y663163D01*
G01X1391501D02*
X1392476Y663885D01*
G01X1391014Y662442D02*
X1391501Y663163D01*
G01X1390527Y660998D02*
X1391014Y662442D01*
G01X1390527Y658111D02*
Y660998D01*
G01X1391014Y656667D02*
X1390527Y658111D01*
G01X1391501Y655946D02*
X1391014Y656667D01*
G01X1392476Y655224D02*
X1391501Y655946D01*
G01X1409040D02*
X1408066Y655224D01*
G01X1409528Y656667D02*
X1409040Y655946D01*
G01X1410015Y658111D02*
X1409528Y656667D01*
G01X1410015Y660998D02*
Y658111D01*
G01X1409528Y662442D02*
X1410015Y660998D01*
G01X1409040Y663163D02*
X1409528Y662442D01*
G01X1408066Y663885D02*
X1409040Y663163D01*
G01X1407092D02*
X1408066Y663885D01*
G01X1406604Y662442D02*
X1407092Y663163D01*
G01X1406117Y660998D02*
X1406604Y662442D01*
G01X1406117Y658111D02*
Y660998D01*
G01X1406604Y656667D02*
X1406117Y658111D01*
G01X1407092Y655946D02*
X1406604Y656667D01*
G01X1408066Y655224D02*
X1407092Y655946D01*
G01X1416836D02*
X1415861Y655224D01*
G01X1417323Y656667D02*
X1416836Y655946D01*
G01X1417810Y658111D02*
X1417323Y656667D01*
G01X1417810Y660998D02*
Y658111D01*
G01X1417323Y662442D02*
X1417810Y660998D01*
G01X1416836Y663163D02*
X1417323Y662442D01*
G01X1415861Y663885D02*
X1416836Y663163D01*
G01X1414887D02*
X1415861Y663885D01*
G01X1414400Y662442D02*
X1414887Y663163D01*
G01X1413913Y660998D02*
X1414400Y662442D01*
G01X1413913Y658111D02*
Y660998D01*
G01X1414400Y656667D02*
X1413913Y658111D01*
G01X1414887Y655946D02*
X1414400Y656667D01*
G01X1415861Y655224D02*
X1414887Y655946D01*
G01X1409040Y675630D02*
X1408066Y674909D01*
G01X1409528Y676352D02*
X1409040Y675630D01*
G01X1410015Y677796D02*
X1409528Y676352D01*
G01X1410015Y680683D02*
Y677796D01*
G01X1409528Y682127D02*
X1410015Y680683D01*
G01X1409040Y682848D02*
X1409528Y682127D01*
G01X1408066Y683570D02*
X1409040Y682848D01*
G01X1407092D02*
X1408066Y683570D01*
G01X1406604Y682127D02*
X1407092Y682848D01*
G01X1406117Y680683D02*
X1406604Y682127D01*
G01X1406117Y677796D02*
Y680683D01*
G01X1406604Y676352D02*
X1406117Y677796D01*
G01X1407092Y675630D02*
X1406604Y676352D01*
G01X1408066Y674909D02*
X1407092Y675630D01*
G01X1416836D02*
X1415861Y674909D01*
G01X1417323Y676352D02*
X1416836Y675630D01*
G01X1417810Y677796D02*
X1417323Y676352D01*
G01X1417810Y680683D02*
Y677796D01*
G01X1417323Y682127D02*
X1417810Y680683D01*
G01X1416836Y682848D02*
X1417323Y682127D01*
G01X1415861Y683570D02*
X1416836Y682848D01*
G01X1414887D02*
X1415861Y683570D01*
G01X1414400Y682127D02*
X1414887Y682848D01*
G01X1413913Y680683D02*
X1414400Y682127D01*
G01X1413913Y677796D02*
Y680683D01*
G01X1414400Y676352D02*
X1413913Y677796D01*
G01X1414887Y675630D02*
X1414400Y676352D01*
G01X1415861Y674909D02*
X1414887Y675630D01*
G01X1399784Y655946D02*
X1400271Y655224D01*
G01X1399784D02*
Y655946D01*
G01X1400271Y655224D02*
X1399784D01*
G01Y675630D02*
X1400271Y674909D01*
G01X1399784D02*
Y675630D01*
G01X1400271Y674909D02*
X1399784D01*
G01X1391014Y675630D02*
X1390527Y676352D01*
G01X1391988Y674909D02*
X1391014Y675630D01*
G01X1392963Y674909D02*
X1391988D01*
G01X1393937Y675630D02*
X1392963Y674909D01*
G01X1394424Y676352D02*
X1393937Y675630D01*
G01X1394912Y677796D02*
X1394424Y676352D01*
G01Y679239D02*
X1394912Y677796D01*
G01X1393937Y679961D02*
X1394424Y679239D01*
G01X1392963Y680683D02*
X1393937Y679961D01*
G01X1391988Y680683D02*
X1392963D01*
G01X1391014Y679961D02*
X1391988Y680683D01*
G01X1391501Y683570D02*
X1391014Y679961D01*
G01X1394424Y683570D02*
X1391501D01*
G01X1383219Y679239D02*
X1386142D01*
G01X1459129Y692428D02*
X1424090D01*
G01X1496924Y720775D02*
X1424090D01*
G01X1394424Y731602D02*
X1390527D01*
G01X1393937Y730158D02*
X1394424Y731602D01*
G01X1393450Y728714D02*
X1393937Y730158D01*
G01X1392963Y726549D02*
X1393450Y728714D01*
G01X1392476Y722940D02*
X1392963Y726549D01*
G01X1406117Y722940D02*
X1410015D01*
G01X1406604Y725106D02*
X1406117Y722940D01*
G01X1407579Y726549D02*
X1406604Y725106D01*
G01X1408553Y727271D02*
X1407579Y726549D01*
G01X1409528Y727993D02*
X1408553Y727271D01*
G01X1410015Y728714D02*
X1409528Y727993D01*
G01X1410015Y730158D02*
Y728714D01*
G01X1409528Y730880D02*
X1410015Y730158D01*
G01X1408553Y731602D02*
X1409528Y730880D01*
G01X1407579Y731602D02*
X1408553D01*
G01X1406604Y730880D02*
X1407579Y731602D01*
G01X1406117Y730158D02*
X1406604Y730880D01*
G01X1393450Y695316D02*
X1392476Y694594D01*
G01X1393937Y696037D02*
X1393450Y695316D01*
G01X1394424Y697481D02*
X1393937Y696037D01*
G01X1394424Y700368D02*
Y697481D01*
G01X1393937Y701812D02*
X1394424Y700368D01*
G01X1393450Y702533D02*
X1393937Y701812D01*
G01X1392476Y703255D02*
X1393450Y702533D01*
G01X1391501D02*
X1392476Y703255D01*
G01X1391014Y701812D02*
X1391501Y702533D01*
G01X1390527Y700368D02*
X1391014Y701812D01*
G01X1390527Y697481D02*
Y700368D01*
G01X1391014Y696037D02*
X1390527Y697481D01*
G01X1391501Y695316D02*
X1391014Y696037D01*
G01X1392476Y694594D02*
X1391501Y695316D01*
G01X1409040D02*
X1408066Y694594D01*
G01X1409528Y696037D02*
X1409040Y695316D01*
G01X1410015Y697481D02*
X1409528Y696037D01*
G01X1410015Y700368D02*
Y697481D01*
G01X1409528Y701812D02*
X1410015Y700368D01*
G01X1409040Y702533D02*
X1409528Y701812D01*
G01X1408066Y703255D02*
X1409040Y702533D01*
G01X1407092D02*
X1408066Y703255D01*
G01X1406604Y701812D02*
X1407092Y702533D01*
G01X1406117Y700368D02*
X1406604Y701812D01*
G01X1406117Y697481D02*
Y700368D01*
G01X1406604Y696037D02*
X1406117Y697481D01*
G01X1407092Y695316D02*
X1406604Y696037D01*
G01X1408066Y694594D02*
X1407092Y695316D01*
G01X1416836D02*
X1415861Y694594D01*
G01X1417323Y696037D02*
X1416836Y695316D01*
G01X1417810Y697481D02*
X1417323Y696037D01*
G01X1417810Y700368D02*
Y697481D01*
G01X1417323Y701812D02*
X1417810Y700368D01*
G01X1416836Y702533D02*
X1417323Y701812D01*
G01X1415861Y703255D02*
X1416836Y702533D01*
G01X1414887D02*
X1415861Y703255D01*
G01X1414400Y701812D02*
X1414887Y702533D01*
G01X1413913Y700368D02*
X1414400Y701812D01*
G01X1413913Y697481D02*
Y700368D01*
G01X1414400Y696037D02*
X1413913Y697481D01*
G01X1414887Y695316D02*
X1414400Y696037D01*
G01X1415861Y694594D02*
X1414887Y695316D01*
G01X1416836Y723662D02*
X1415861Y722940D01*
G01X1417323Y724384D02*
X1416836Y723662D01*
G01X1417810Y725827D02*
X1417323Y724384D01*
G01X1417810Y728714D02*
Y725827D01*
G01X1417323Y730158D02*
X1417810Y728714D01*
G01X1416836Y730880D02*
X1417323Y730158D01*
G01X1415861Y731602D02*
X1416836Y730880D01*
G01X1414887D02*
X1415861Y731602D01*
G01X1414400Y730158D02*
X1414887Y730880D01*
G01X1413913Y728714D02*
X1414400Y730158D01*
G01X1413913Y725827D02*
Y728714D01*
G01X1414400Y724384D02*
X1413913Y725827D01*
G01X1414887Y723662D02*
X1414400Y724384D01*
G01X1415861Y722940D02*
X1414887Y723662D01*
G01X1399784Y695316D02*
X1400271Y694594D01*
G01X1399784D02*
Y695316D01*
G01X1400271Y694594D02*
X1399784D01*
G01Y723662D02*
X1400271Y722940D01*
G01X1399784D02*
Y723662D01*
G01X1400271Y722940D02*
X1399784D01*
G01X1384680Y703255D02*
Y694594D01*
G01Y731602D02*
Y722940D01*
G01X1457104Y251258D02*
X1453954D01*
G01X1469736Y309345D02*
X1457104Y251258D01*
G01X1441882Y254867D02*
X1440908Y253423D01*
G01X1442370Y257032D02*
X1441882Y254867D01*
G01X1442370Y258476D02*
Y257032D01*
G01X1441882Y260641D02*
X1442370Y258476D01*
G01X1440908Y262085D02*
X1441882Y260641D01*
G01X1434087Y254867D02*
X1433113Y253423D01*
G01X1434574Y257032D02*
X1434087Y254867D01*
G01X1434574Y258476D02*
Y257032D01*
G01X1434087Y260641D02*
X1434574Y258476D01*
G01X1433113Y262085D02*
X1434087Y260641D01*
G01X1427753Y262085D02*
Y253423D01*
G01X1454563Y294565D02*
G03X1458500Y290628I3937J0D01*
G01X1475823Y314250D02*
G03I-5020J0D01*
G01X1482614D02*
G03I-11811J0D01*
G01X1458500Y290628D02*
X2178972D01*
G01X1454563Y329998D02*
Y294565D01*
G01X1473075Y325840D02*
X1488709Y405589D01*
G01X1458500Y333935D02*
G03X1454563Y329998I0J-3937D01*
G01X1488421Y333935D02*
X1458500D01*
G01X1456242Y589776D02*
X1456964Y590263D01*
G01Y589776D02*
X1456242D01*
G01X1456964Y590263D02*
Y589776D01*
G01X1472482D02*
X1473204Y590263D01*
G01Y589776D02*
X1472482D01*
G01X1449746Y596597D02*
X1449024Y597084D01*
G01X1451189Y596110D02*
X1449746Y596597D01*
G01X1454077Y596110D02*
X1451189D01*
G01X1455520Y596597D02*
X1454077Y596110D01*
G01X1456242Y597084D02*
X1455520Y596597D01*
G01X1456242Y583442D02*
X1456964Y582468D01*
G01X1455520Y583929D02*
X1456242Y583442D01*
G01X1454077Y584417D02*
X1455520Y583929D01*
G01X1451189Y584417D02*
X1454077D01*
G01X1449746Y583929D02*
X1451189Y584417D01*
G01X1449024Y583442D02*
X1449746Y583929D01*
G01X1448302Y582468D02*
X1449024Y583442D01*
G01Y581493D02*
X1448302Y582468D01*
G01X1449746Y581006D02*
X1449024Y581493D01*
G01X1451189Y580519D02*
X1449746Y581006D01*
G01X1454077Y580519D02*
X1451189D01*
G01X1455520Y581006D02*
X1454077Y580519D01*
G01X1456242Y581493D02*
X1455520Y581006D01*
G01X1456964Y582468D02*
X1456242Y581493D01*
G01X1471039Y580519D02*
Y584904D01*
G01X1464542Y583929D02*
X1471039Y580519D01*
G01X1473204Y583929D02*
X1464542D01*
G01X1459129Y653058D02*
Y614082D01*
G01X1468151Y606341D02*
X1468873Y607315D01*
G01X1467430D02*
X1468151Y606341D01*
G01X1466708Y607802D02*
X1467430Y607315D01*
G01X1465986Y607802D02*
X1466708D01*
G01X1465264Y607315D02*
X1465986Y607802D01*
G01X1464542Y606341D02*
X1465264Y607315D01*
G01X1464542Y605366D02*
Y606341D01*
G01X1465264Y604392D02*
X1464542Y605366D01*
G01X1456242Y606828D02*
X1456964Y605854D01*
G01X1455520Y607315D02*
X1456242Y606828D01*
G01X1454077Y607802D02*
X1455520Y607315D01*
G01X1451189Y607802D02*
X1454077D01*
G01X1449746Y607315D02*
X1451189Y607802D01*
G01X1449024Y606828D02*
X1449746Y607315D01*
G01X1448302Y605854D02*
X1449024Y606828D01*
G01Y604879D02*
X1448302Y605854D01*
G01X1449746Y604392D02*
X1449024Y604879D01*
G01X1451189Y603905D02*
X1449746Y604392D01*
G01X1454077Y603905D02*
X1451189D01*
G01X1455520Y604392D02*
X1454077Y603905D01*
G01X1456242Y604879D02*
X1455520Y604392D01*
G01X1456964Y605854D02*
X1456242Y604879D01*
G01Y599033D02*
X1456964Y598058D01*
G01X1455520Y599520D02*
X1456242Y599033D01*
G01X1454077Y600007D02*
X1455520Y599520D01*
G01X1451189Y600007D02*
X1454077D01*
G01X1449746Y599520D02*
X1451189Y600007D01*
G01X1449024Y599033D02*
X1449746Y599520D01*
G01X1448302Y598058D02*
X1449024Y599033D01*
G01Y597084D02*
X1448302Y598058D01*
G01X1456964D02*
X1456242Y597084D01*
G01X1472482Y604392D02*
X1471760Y603905D01*
G01X1473204Y605366D02*
X1472482Y604392D01*
G01Y607315D02*
X1473204Y606341D01*
G01X1471760Y607802D02*
X1472482Y607315D01*
G01X1471039Y608290D02*
X1471760Y607802D01*
G01X1470317Y608290D02*
X1471039D01*
G01X1468873Y607315D02*
X1470317Y608290D01*
G01X1464542Y598058D02*
X1473204D01*
G01X1468151Y605366D02*
Y606341D01*
G01X1463066Y692428D02*
G03X1459129Y688491I0J-3937D01*
G01Y653058D02*
G03X1463066Y649121I3937J0D01*
G01X1480389Y672743D02*
G03I-5020J0D01*
G01X1487180D02*
G03I-11811J0D01*
G01X1463066Y649121D02*
X2183539D01*
G01X1459129Y688491D02*
Y653058D01*
G01X1492987Y692428D02*
X1463066D01*
G01X1504668Y-618663D02*
Y-637600D01*
G01X1505832Y309766D02*
X1567447Y231573D01*
G01X1508008Y314250D02*
G03I-5709J0D01*
G01X1488421Y333935D02*
G03X1492358Y337872I0J3937D01*
G01Y358345D02*
Y337872D01*
G01X1489057Y405589D02*
X1790763D01*
G01X1488709D02*
X1489057D01*
G01X1496295Y362282D02*
G03X1492358Y358345I0J-3937D01*
G01X1523854D02*
G03X1519917Y362282I-3937J0D01*
G01D02*
X1496295D01*
G01X1514030Y405589D02*
X1521248Y418581D01*
G01X1499667Y409919D02*
X1504052D01*
G01X1503077Y416415D02*
X1499667Y409919D01*
G01X1503077Y407754D02*
Y416415D01*
G01X1514030Y409919D02*
X1513309Y412085D01*
G01X1515474Y408476D02*
X1514030Y409919D01*
G01X1517639Y407754D02*
X1515474Y408476D01*
G01X1519805D02*
X1517639Y407754D01*
G01X1521248Y409919D02*
X1519805Y408476D01*
G01Y415694D02*
X1521248Y414250D01*
G01X1517639Y416415D02*
X1519805Y415694D01*
G01X1515474D02*
X1517639Y416415D01*
G01X1514030Y414250D02*
X1515474Y415694D01*
G01X1513309Y412085D02*
X1514030Y414250D01*
G01X1507949Y412085D02*
X1510873D01*
G01X1492970Y552062D02*
X1794676D01*
G01X1490922D02*
X1492970D01*
G01X1476879Y661029D02*
X1490922Y552062D01*
G01X1473204Y590263D02*
Y589776D01*
G01X1503978D02*
X1504700Y590263D01*
G01Y589776D02*
X1503978D01*
G01X1504700Y590263D02*
Y589776D01*
G01X1503580Y556393D02*
X1507965D01*
G01X1506990Y562889D02*
X1503580Y556393D01*
G01X1506990Y554227D02*
Y562889D01*
G01X1504700Y580519D02*
Y584417D01*
G01X1502535Y581006D02*
X1504700Y580519D01*
G01X1501091Y581981D02*
X1502535Y581006D01*
G01X1499647Y583929D02*
X1501091Y581981D01*
G01X1498926Y584417D02*
X1499647Y583929D01*
G01X1497482Y584417D02*
X1498926D01*
G01X1496760Y583929D02*
X1497482Y584417D01*
G01X1496039Y582955D02*
X1496760Y583929D01*
G01X1496039Y581981D02*
Y582955D01*
G01X1496760Y581006D02*
X1496039Y581981D01*
G01X1497482Y580519D02*
X1496760Y581006D01*
G01X1517943Y556393D02*
X1517222Y558558D01*
G01X1519387Y554949D02*
X1517943Y556393D01*
G01X1521552Y554227D02*
X1519387Y554949D01*
G01Y562167D02*
X1521552Y562889D01*
G01X1517943Y560723D02*
X1519387Y562167D01*
G01X1517222Y558558D02*
X1517943Y560723D01*
G01X1496039Y574672D02*
X1504700D01*
G01X1511862Y558558D02*
X1514786D01*
G01X1517943Y552062D02*
X1525161Y565054D01*
G01X1475369Y668806D02*
Y614082D01*
G01X1506865Y668806D02*
Y614082D01*
G01X1499647Y606341D02*
X1500369Y607315D01*
G01X1498926D02*
X1499647Y606341D01*
G01X1498204Y607802D02*
X1498926Y607315D01*
G01X1497482Y607802D02*
X1498204D01*
G01X1496760Y607315D02*
X1497482Y607802D01*
G01X1496039Y606341D02*
X1496760Y607315D01*
G01X1496039Y605366D02*
Y606341D01*
G01X1496760Y604392D02*
X1496039Y605366D01*
G01X1473204Y606341D02*
Y605366D01*
G01X1503978Y604392D02*
X1503256Y603905D01*
G01X1504700Y605366D02*
X1503978Y604392D01*
G01X1504700Y606341D02*
Y605366D01*
G01X1503978Y607315D02*
X1504700Y606341D01*
G01X1503256Y607802D02*
X1503978Y607315D01*
G01X1502535Y608290D02*
X1503256Y607802D01*
G01X1501813Y608290D02*
X1502535D01*
G01X1500369Y607315D02*
X1501813Y608290D01*
G01X1496039Y598058D02*
X1504700D01*
G01X1499647Y605366D02*
Y606341D01*
G01X1512574Y672743D02*
G03I-5709J0D01*
G01X1496924Y720775D02*
Y759751D01*
G01X1513657Y715263D02*
G03X1514838I591J0D01*
G01Y708964D02*
G03X1513657I-590J0D01*
G01X1511688D02*
G03X1510507I-591J0D01*
G01Y715263D02*
G03X1511688I591J0D01*
G01X1513657D02*
G03X1514838I591J0D01*
G01Y708964D02*
G03X1513657I-590J0D01*
G01X1511688D02*
G03X1510507I-591J0D01*
G01Y715263D02*
G03X1511688I591J0D01*
G01X1500861Y720775D02*
G03X1496924Y716838I0J-3937D01*
G01X1492987Y692428D02*
G03X1496924Y696365I0J3937D01*
G01X1513968Y713996D02*
X1513927Y713987D01*
G01X1524483Y720775D02*
X1500861D01*
G01X1513066Y715263D02*
X1515428D01*
G01X1509916D02*
X1512279D01*
G01X1510507D02*
X1509720D01*
G01X1510507D02*
X1509720D01*
G01X1513657D02*
X1511688D01*
G01X1513657D02*
X1511688D01*
G01X1515625D02*
X1514838D01*
G01X1515625D02*
X1514838D01*
G01X1515625Y714279D02*
X1509720D01*
G01X1514657Y714205D02*
X1514706D01*
G01X1514493D02*
X1514542D01*
G01X1514214D02*
X1514288D01*
G01X1514099D02*
X1514149D01*
G01X1513730D02*
X1513927D01*
G01X1513935Y714163D02*
X1513780D01*
G01X1509720Y714082D02*
X1515625D01*
G01X1513780Y714038D02*
X1513935D01*
G01X1513927Y713987D02*
X1513780D01*
G01Y713811D02*
X1513730D01*
G01X1514706D02*
X1514657D01*
G01X1514542D02*
X1514469D01*
G01X1514263D02*
X1514214D01*
G01X1514149D02*
X1514099D01*
G01X1512279Y713688D02*
X1509916D01*
G01X1515428D02*
X1513066D01*
G01X1512279Y710539D02*
X1509916D01*
G01X1515428D02*
X1513066D01*
G01X1509720Y710145D02*
X1515625D01*
G01Y709948D02*
X1509720D01*
G01X1514838Y708964D02*
X1515625D01*
G01X1514838D02*
X1515625D01*
G01X1513066D02*
X1515428D01*
G01X1511688D02*
X1513657D01*
G01X1511688D02*
X1513657D01*
G01X1509916D02*
X1512279D01*
G01X1509720D02*
X1510507D01*
G01X1509720D02*
X1510507D01*
G01X1513927Y714205D02*
X1513968Y714197D01*
G01X1513960Y714155D02*
X1513935Y714163D01*
G01Y714038D02*
X1513960Y714046D01*
G01X1513968Y714197D02*
X1514001Y714172D01*
G01X1513976Y714138D02*
X1513960Y714155D01*
G01X1514001Y714021D02*
X1513968Y713996D01*
G01X1514001Y714172D02*
X1514026Y714138D01*
G01X1513960Y714046D02*
X1513976Y714063D01*
G01X1514469Y713811D02*
X1514263Y714155D01*
G01X1514288Y714205D02*
X1514493Y713870D01*
G01X1514657Y714138D02*
X1514608Y714079D01*
G01Y714146D02*
X1514657Y714205D01*
G01X1514026Y714138D02*
X1514034Y714113D01*
G01X1513985D02*
X1513976Y714138D01*
G01X1514026Y714054D02*
X1514001Y714021D01*
G01X1514034Y714079D02*
X1514026Y714054D01*
G01X1513976Y714063D02*
X1513985Y714088D01*
G01X1515625Y708964D02*
Y715263D01*
G01Y708964D02*
Y715263D01*
G01X1515428Y708964D02*
Y710539D01*
G01Y715263D02*
Y713688D01*
G01X1514706Y714205D02*
Y713811D01*
G01X1514657D02*
Y714138D01*
G01X1514608Y714079D02*
Y714146D01*
G01X1514542Y714205D02*
Y713811D01*
G01X1514493Y713870D02*
Y714205D01*
G01X1514263Y714155D02*
Y713811D01*
G01X1514214D02*
Y714205D01*
G01X1514149D02*
Y713811D01*
G01X1514099D02*
Y714205D01*
G01X1514034Y714113D02*
Y714079D01*
G01X1513985Y714088D02*
Y714113D01*
G01X1513780Y714163D02*
Y714038D01*
G01Y713987D02*
Y713811D01*
G01X1513730D02*
Y714205D01*
G01X1513066Y713688D02*
Y715263D01*
G01Y710539D02*
Y708964D01*
G01X1512279D02*
Y710539D01*
G01Y715263D02*
Y713688D01*
G01X1509916D02*
Y715263D01*
G01Y710539D02*
Y708964D01*
G01X1509720D02*
Y715263D01*
G01D02*
Y708964D01*
G01X1496924Y716838D02*
Y696365D01*
G01X1494037Y775288D02*
X1494759Y775775D01*
G01Y775288D02*
X1494037D01*
G01X1494759Y775775D02*
Y775288D01*
G01X1494037Y767005D02*
X1493315Y766518D01*
G01X1494759Y767980D02*
X1494037Y767005D01*
G01Y768954D02*
X1494759Y767980D01*
G01X1493315Y769441D02*
X1494037Y768954D01*
G01X1491872Y769928D02*
X1493315Y769441D01*
G01X1488985Y769928D02*
X1491872D01*
G01X1487541Y769441D02*
X1488985Y769928D01*
G01X1486819Y768954D02*
X1487541Y769441D01*
G01X1486098Y767980D02*
X1486819Y768954D01*
G01Y767005D02*
X1486098Y767980D01*
G01X1487541Y766518D02*
X1486819Y767005D01*
G01X1488985Y766031D02*
X1487541Y766518D01*
G01X1490428D02*
X1488985Y766031D01*
G01X1491150Y767980D02*
X1490428Y766518D01*
G01Y769441D02*
X1491150Y767980D01*
G01X1488985Y769928D02*
X1490428Y769441D01*
G01X1486819Y784545D02*
X1487541Y785032D01*
G01X1486098Y783570D02*
X1486819Y784545D01*
G01Y782596D02*
X1486098Y783570D01*
G01X1487541Y782109D02*
X1486819Y782596D01*
G01X1488985Y781621D02*
X1487541Y782109D01*
G01X1491872Y781621D02*
X1488985D01*
G01X1493315Y782109D02*
X1491872Y781621D01*
G01X1494037Y782596D02*
X1493315Y782109D01*
G01X1494759Y783570D02*
X1494037Y782596D01*
G01Y784545D02*
X1494759Y783570D01*
G01X1493315Y785032D02*
X1494037Y784545D01*
G01X1491872Y785519D02*
X1493315Y785032D01*
G01X1490428D02*
X1491872Y785519D01*
G01X1489706Y783570D02*
X1490428Y785032D01*
G01Y782109D02*
X1489706Y783570D01*
G01X1491872Y781621D02*
X1490428Y782109D01*
G01X1517594Y777724D02*
Y773826D01*
G01X1519037Y777237D02*
X1517594Y777724D01*
G01X1520481Y776749D02*
X1519037Y777237D01*
G01X1522646Y776262D02*
X1520481Y776749D01*
G01X1517594Y767980D02*
X1526255D01*
G01X1494037Y792340D02*
X1494759Y791365D01*
G01X1493315Y792827D02*
X1494037Y792340D01*
G01X1491872Y793314D02*
X1493315Y792827D01*
G01X1488985Y793314D02*
X1491872D01*
G01X1487541Y792827D02*
X1488985Y793314D01*
G01X1486819Y792340D02*
X1487541Y792827D01*
G01X1486098Y791365D02*
X1486819Y792340D01*
G01Y790391D02*
X1486098Y791365D01*
G01X1487541Y789904D02*
X1486819Y790391D01*
G01X1488985Y789417D02*
X1487541Y789904D01*
G01X1491872Y789417D02*
X1488985D01*
G01X1493315Y789904D02*
X1491872Y789417D01*
G01X1494037Y790391D02*
X1493315Y789904D01*
G01X1494759Y791365D02*
X1494037Y790391D01*
G01X1520481Y801109D02*
X1523368D01*
G01X1519037Y800622D02*
X1520481Y801109D01*
G01X1518315Y800135D02*
X1519037Y800622D01*
G01X1517594Y799161D02*
X1518315Y800135D01*
G01Y798186D02*
X1517594Y799161D01*
G01X1519037Y797699D02*
X1518315Y798186D01*
G01X1520481Y797212D02*
X1519037Y797699D01*
G01X1523368Y797212D02*
X1520481D01*
G01X1518315Y792340D02*
X1519037Y792827D01*
G01X1517594Y791365D02*
X1518315Y792340D01*
G01Y790391D02*
X1517594Y791365D01*
G01X1519037Y789904D02*
X1518315Y790391D01*
G01X1520481Y789417D02*
X1519037Y789904D01*
G01X1523368Y789417D02*
X1520481D01*
G01X1504668Y1559093D02*
Y1540156D01*
G01X1568499Y-618663D02*
X1958262D01*
G01X1567447Y231573D02*
X1570597D01*
G01X1523854Y337872D02*
G03X1527791Y333935I3937J0D01*
G01X1610665D02*
X1527791D01*
G01X1523854Y337872D02*
Y358345D01*
G01X1521970Y412085D02*
X1521248Y409919D01*
G01Y414250D02*
X1521970Y412085D01*
G01X1529729Y415694D02*
X1530216Y414972D01*
G01X1528755Y416415D02*
X1529729Y415694D01*
G01X1527780D02*
X1528755Y416415D01*
G01X1527293Y414972D02*
X1527780Y415694D01*
G01X1526806Y413528D02*
X1527293Y414972D01*
G01X1526806Y410641D02*
Y413528D01*
G01X1527293Y409198D02*
X1526806Y410641D01*
G01X1527780Y408476D02*
X1527293Y409198D01*
G01X1528755Y407754D02*
X1527780Y408476D01*
G01X1529729D02*
X1528755Y407754D01*
G01X1530216Y409198D02*
X1529729Y408476D01*
G01X1530703Y410641D02*
X1530216Y409198D01*
G01Y412085D02*
X1530703Y410641D01*
G01X1528755Y412806D02*
X1530216Y412085D01*
G01X1527293D02*
X1528755Y412806D01*
G01X1526806Y410641D02*
X1527293Y412085D01*
G01X1568218D02*
X1565782D01*
G01X1569193Y412806D02*
X1568218Y412085D01*
G01Y416415D02*
X1569193Y415694D01*
G01X1565782Y416415D02*
X1568218D01*
G01X1565782Y407754D02*
Y416415D01*
G01X1559449Y409198D02*
X1560423Y407754D01*
G01X1558961Y411363D02*
X1559449Y409198D01*
G01X1558961Y412806D02*
Y411363D01*
G01X1559449Y414972D02*
X1558961Y412806D01*
G01X1560423Y416415D02*
X1559449Y414972D01*
G01X1545320Y408476D02*
X1544345Y407754D01*
G01X1545807Y409198D02*
X1545320Y408476D01*
G01X1546294Y410641D02*
X1545807Y409198D01*
G01X1546294Y413528D02*
Y410641D01*
G01X1545807Y414972D02*
X1546294Y413528D01*
G01X1545320Y415694D02*
X1545807Y414972D01*
G01X1544345Y416415D02*
X1545320Y415694D01*
G01X1543371D02*
X1544345Y416415D01*
G01X1542884Y414972D02*
X1543371Y415694D01*
G01X1542396Y413528D02*
X1542884Y414972D01*
G01X1542396Y410641D02*
Y413528D01*
G01X1542884Y409198D02*
X1542396Y410641D01*
G01X1543371Y408476D02*
X1542884Y409198D01*
G01X1544345Y407754D02*
X1543371Y408476D01*
G01X1553115D02*
X1552141Y407754D01*
G01X1553602Y409198D02*
X1553115Y408476D01*
G01X1554089Y410641D02*
X1553602Y409198D01*
G01X1554089Y413528D02*
Y410641D01*
G01X1553602Y414972D02*
X1554089Y413528D01*
G01X1553115Y415694D02*
X1553602Y414972D01*
G01X1552141Y416415D02*
X1553115Y415694D01*
G01X1551166D02*
X1552141Y416415D01*
G01X1550679Y414972D02*
X1551166Y415694D01*
G01X1550192Y413528D02*
X1550679Y414972D01*
G01X1550192Y410641D02*
Y413528D01*
G01X1550679Y409198D02*
X1550192Y410641D01*
G01X1551166Y408476D02*
X1550679Y409198D01*
G01X1552141Y407754D02*
X1551166Y408476D01*
G01X1536063D02*
X1536550Y407754D01*
G01X1536063D02*
Y408476D01*
G01X1536550Y407754D02*
X1536063D01*
G01X1549233Y554949D02*
X1548258Y554227D01*
G01X1549720Y555671D02*
X1549233Y554949D01*
G01X1550207Y557114D02*
X1549720Y555671D01*
G01X1550207Y560002D02*
Y557114D01*
G01X1549720Y561445D02*
X1550207Y560002D01*
G01X1549233Y562167D02*
X1549720Y561445D01*
G01X1548258Y562889D02*
X1549233Y562167D01*
G01X1547284D02*
X1548258Y562889D01*
G01X1546797Y561445D02*
X1547284Y562167D01*
G01X1546309Y560002D02*
X1546797Y561445D01*
G01X1546309Y557114D02*
Y560002D01*
G01X1546797Y555671D02*
X1546309Y557114D01*
G01X1547284Y554949D02*
X1546797Y555671D01*
G01X1548258Y554227D02*
X1547284Y554949D01*
G01X1557028D02*
X1556054Y554227D01*
G01X1557515Y555671D02*
X1557028Y554949D01*
G01X1558002Y557114D02*
X1557515Y555671D01*
G01X1558002Y560002D02*
Y557114D01*
G01X1557515Y561445D02*
X1558002Y560002D01*
G01X1557028Y562167D02*
X1557515Y561445D01*
G01X1556054Y562889D02*
X1557028Y562167D01*
G01X1555079D02*
X1556054Y562889D01*
G01X1554592Y561445D02*
X1555079Y562167D01*
G01X1554105Y560002D02*
X1554592Y561445D01*
G01X1554105Y557114D02*
Y560002D01*
G01X1554592Y555671D02*
X1554105Y557114D01*
G01X1555079Y554949D02*
X1554592Y555671D01*
G01X1556054Y554227D02*
X1555079Y554949D01*
G01X1523718D02*
X1521552Y554227D01*
G01X1525161Y556393D02*
X1523718Y554949D01*
G01X1525883Y558558D02*
X1525161Y556393D01*
G01Y560723D02*
X1525883Y558558D01*
G01X1523718Y562167D02*
X1525161Y560723D01*
G01X1521552Y562889D02*
X1523718Y562167D01*
G01X1533642D02*
X1534129Y561445D01*
G01X1532668Y562889D02*
X1533642Y562167D01*
G01X1531693D02*
X1532668Y562889D01*
G01X1531206Y561445D02*
X1531693Y562167D01*
G01X1530719Y560002D02*
X1531206Y561445D01*
G01X1530719Y557114D02*
Y560002D01*
G01X1531206Y555671D02*
X1530719Y557114D01*
G01X1531693Y554949D02*
X1531206Y555671D01*
G01X1532668Y554227D02*
X1531693Y554949D01*
G01X1533642D02*
X1532668Y554227D01*
G01X1534129Y555671D02*
X1533642Y554949D01*
G01X1534617Y557114D02*
X1534129Y555671D01*
G01Y558558D02*
X1534617Y557114D01*
G01X1532668Y559280D02*
X1534129Y558558D01*
G01X1531206D02*
X1532668Y559280D01*
G01X1530719Y557114D02*
X1531206Y558558D01*
G01X1563362Y555671D02*
X1564336Y554227D01*
G01X1562874Y557836D02*
X1563362Y555671D01*
G01X1562874Y559280D02*
Y557836D01*
G01X1563362Y561445D02*
X1562874Y559280D01*
G01X1564336Y562889D02*
X1563362Y561445D01*
G01X1539976Y554949D02*
X1540463Y554227D01*
G01X1539976D02*
Y554949D01*
G01X1540463Y554227D02*
X1539976D01*
G01X1528420Y720775D02*
Y759751D01*
G01X1556783Y726877D02*
X1555809D01*
G01X1557758Y727599D02*
X1556783Y726877D01*
G01X1558245Y728321D02*
X1557758Y727599D01*
G01X1558732Y729043D02*
X1558245Y728321D01*
G01X1558732Y729764D02*
Y729043D01*
G01X1558245Y730486D02*
X1558732Y729764D01*
G01X1557758Y731208D02*
X1558245Y730486D01*
G01X1556783Y731930D02*
X1557758Y731208D01*
G01X1555809Y731930D02*
X1556783D01*
G01X1554835Y731208D02*
X1555809Y731930D01*
G01X1554347Y730486D02*
X1554835Y731208D01*
G01X1553860Y729764D02*
X1554347Y730486D01*
G01X1553860Y729043D02*
Y729764D01*
G01X1554347Y728321D02*
X1553860Y729043D01*
G01X1554835Y727599D02*
X1554347Y728321D01*
G01X1555809Y726877D02*
X1554835Y727599D01*
G01X1557758Y732651D02*
X1556783Y731930D01*
G01X1558245Y733373D02*
X1557758Y732651D01*
G01X1558245Y734095D02*
Y733373D01*
G01X1557758Y734817D02*
X1558245Y734095D01*
G01X1556783Y735539D02*
X1557758Y734817D01*
G01X1555809Y735539D02*
X1556783D01*
G01X1554835Y734817D02*
X1555809Y735539D01*
G01X1554347Y734095D02*
X1554835Y734817D01*
G01X1554347Y733373D02*
Y734095D01*
G01X1554835Y732651D02*
X1554347Y733373D01*
G01X1555809Y731930D02*
X1554835Y732651D01*
G01X1563604Y727599D02*
X1564091Y726877D01*
G01X1563604D02*
Y727599D01*
G01X1564091Y726877D02*
X1563604D01*
G01X1528420Y716838D02*
G03X1524483Y720775I-3937J0D01*
G01X1528420Y696365D02*
G03X1532357Y692428I3937J0D01*
G01X1615231D02*
X1532357D01*
G01X1548501Y735539D02*
Y726877D01*
G01X1528420Y696365D02*
Y716838D01*
G01X1525533Y783083D02*
X1526255Y783570D01*
G01Y783083D02*
X1525533D01*
G01X1526255Y783570D02*
Y783083D01*
G01Y775775D02*
X1522646Y776262D01*
G01X1525533Y800135D02*
X1526255Y799161D01*
G01X1524811Y800622D02*
X1525533Y800135D01*
G01X1523368Y801109D02*
X1524811Y800622D01*
G01Y797699D02*
X1523368Y797212D01*
G01X1525533Y798186D02*
X1524811Y797699D01*
G01X1526255Y799161D02*
X1525533Y798186D01*
G01X1524811Y789904D02*
X1523368Y789417D01*
G01X1525533Y790391D02*
X1524811Y789904D01*
G01X1526255Y791365D02*
X1525533Y790391D01*
G01Y792340D02*
X1526255Y791365D01*
G01X1524811Y792827D02*
X1525533Y792340D01*
G01X1523368Y793314D02*
X1524811Y792827D01*
G01X1521924D02*
X1523368Y793314D01*
G01X1521203Y791365D02*
X1521924Y792827D01*
G01Y789904D02*
X1521203Y791365D01*
G01X1523368Y789417D02*
X1521924Y789904D01*
G01X1570597Y231573D02*
X1677421D01*
G01X1579980Y235904D02*
X1579258Y238069D01*
G01X1581424Y234460D02*
X1579980Y235904D01*
G01X1583589Y233738D02*
X1581424Y234460D01*
G01X1585754D02*
X1583589Y233738D01*
G01X1587198Y235904D02*
X1585754Y234460D01*
G01X1587920Y238069D02*
X1587198Y235904D01*
G01Y240234D02*
X1587920Y238069D01*
G01X1585754Y241678D02*
X1587198Y240234D01*
G01X1583589Y242400D02*
X1585754Y241678D01*
G01X1581424D02*
X1583589Y242400D01*
G01X1579980Y240234D02*
X1581424Y241678D01*
G01X1579258Y238069D02*
X1579980Y240234D01*
G01X1616142Y239512D02*
X1616629Y240956D01*
G01X1616142Y236625D02*
Y239512D01*
G01X1616629Y235182D02*
X1616142Y236625D01*
G01X1609321Y234460D02*
X1608833Y235182D01*
G01X1610295Y233738D02*
X1609321Y234460D01*
G01X1611270D02*
X1610295Y233738D01*
G01X1611757Y235182D02*
X1611270Y234460D01*
G01X1612244Y236625D02*
X1611757Y235182D01*
G01X1612244Y239512D02*
Y236625D01*
G01X1611757Y240956D02*
X1612244Y239512D01*
G01X1611270Y241678D02*
X1611757Y240956D01*
G01X1610295Y242400D02*
X1611270Y241678D01*
G01X1609321D02*
X1610295Y242400D01*
G01X1608833Y240956D02*
X1609321Y241678D01*
G01X1608346Y239512D02*
X1608833Y240956D01*
G01Y238069D02*
X1608346Y239512D01*
G01X1610295Y237347D02*
X1608833Y238069D01*
G01X1611757D02*
X1610295Y237347D01*
G01X1612244Y239512D02*
X1611757Y238069D01*
G01X1596653Y239512D02*
X1596166Y238791D01*
G01X1596653Y240956D02*
Y239512D01*
G01X1596166Y241678D02*
X1596653Y240956D01*
G01X1595192Y242400D02*
X1596166Y241678D01*
G01X1594217Y242400D02*
X1595192D01*
G01X1593243Y241678D02*
X1594217Y242400D01*
G01X1592756Y240956D02*
X1593243Y241678D01*
G01X1602013Y234460D02*
X1602500Y233738D01*
G01X1602013D02*
Y234460D01*
G01X1602500Y233738D02*
X1602013D01*
G01X1592756D02*
X1596653D01*
G01X1593243Y235904D02*
X1592756Y233738D01*
G01X1594217Y237347D02*
X1593243Y235904D01*
G01X1596166Y238791D02*
X1594217Y237347D01*
G01X1579980Y231573D02*
X1587198Y244565D01*
G01X1615389Y290628D02*
X1680744D01*
G01X1615389Y332360D02*
Y290628D01*
G01X1610665Y333935D02*
G03X1614602Y337872I0J3937D01*
G01X1680744Y332360D02*
X1615389D01*
G01X1614602Y337872D02*
Y362282D01*
G01X1618539Y366219D02*
G03X1614602Y362282I0J-3937D01*
G01X1569680Y413528D02*
X1569193Y412806D01*
G01X1569680Y414972D02*
Y413528D01*
G01X1569193Y415694D02*
X1569680Y414972D01*
G01X1575526Y416415D02*
X1577962Y407754D01*
G01X1573090D02*
X1575526Y416415D01*
G01X1598425Y409198D02*
X1599399Y407754D01*
G01X1597938Y411363D02*
X1598425Y409198D01*
G01X1597938Y412806D02*
Y411363D01*
G01X1598425Y414972D02*
X1597938Y412806D01*
G01X1599399Y416415D02*
X1598425Y414972D01*
G01X1615964Y415694D02*
X1616939Y414250D01*
G01X1614990Y416415D02*
X1615964Y415694D01*
G01X1614016Y416415D02*
X1614990D01*
G01X1613041Y415694D02*
X1614016Y416415D01*
G01X1612067Y414250D02*
X1613041Y415694D01*
G01X1608656Y407754D02*
Y416415D01*
G01X1604759D02*
X1608656Y407754D01*
G01X1604759D02*
Y416415D01*
G01X1581373Y407754D02*
Y416415D01*
G01X1583322Y407754D02*
X1581373D01*
G01X1584296Y408476D02*
X1583322Y407754D01*
G01X1585271Y409919D02*
X1584296Y408476D01*
G01X1585758Y412085D02*
X1585271Y409919D01*
G01Y414250D02*
X1585758Y412085D01*
G01X1611580D02*
X1612067Y414250D01*
G01Y409919D02*
X1611580Y412085D01*
G01X1612554Y409198D02*
X1612067Y409919D01*
G01X1613041Y408476D02*
X1612554Y409198D01*
G01X1614016Y407754D02*
X1613041Y408476D01*
G01X1614990Y407754D02*
X1614016D01*
G01X1615964Y408476D02*
X1614990Y407754D01*
G01X1616939Y409919D02*
X1615964Y408476D01*
G01X1591604Y409198D02*
X1590630Y407754D01*
G01X1592091Y411363D02*
X1591604Y409198D01*
G01X1592091Y412806D02*
Y411363D01*
G01X1591604Y414972D02*
X1592091Y412806D01*
G01X1590630Y416415D02*
X1591604Y414972D01*
G01X1584296Y415694D02*
X1585271Y414250D01*
G01X1583322Y416415D02*
X1584296Y415694D01*
G01X1581373Y416415D02*
X1583322D01*
G01X1574065Y410641D02*
X1576988D01*
G01X1572131Y558558D02*
X1569695D01*
G01X1573106Y559280D02*
X1572131Y558558D01*
G01X1573593Y560002D02*
X1573106Y559280D01*
G01X1573593Y561445D02*
Y560002D01*
G01X1573106Y562167D02*
X1573593Y561445D01*
G01X1572131Y562889D02*
X1573106Y562167D01*
G01X1569695Y562889D02*
X1572131D01*
G01X1569695Y554227D02*
Y562889D01*
G01X1595517Y555671D02*
X1594543Y554227D01*
G01X1596004Y557836D02*
X1595517Y555671D01*
G01X1596004Y559280D02*
Y557836D01*
G01X1595517Y561445D02*
X1596004Y559280D01*
G01X1594543Y562889D02*
X1595517Y561445D01*
G01X1585286Y554227D02*
Y562889D01*
G01X1587235Y554227D02*
X1585286D01*
G01X1588209Y554949D02*
X1587235Y554227D01*
G01X1588696Y555671D02*
X1588209Y554949D01*
G01X1589183Y556393D02*
X1588696Y555671D01*
G01X1589671Y558558D02*
X1589183Y556393D01*
G01Y560723D02*
X1589671Y558558D01*
G01X1615980Y560723D02*
X1616467Y561445D01*
G01X1615493Y558558D02*
X1615980Y560723D01*
G01Y556393D02*
X1615493Y558558D01*
G01X1612569Y554227D02*
Y562889D01*
G01X1608672D02*
X1612569Y554227D01*
G01X1608672D02*
Y562889D01*
G01X1579439D02*
X1581875Y554227D01*
G01X1577003D02*
X1579439Y562889D01*
G01X1588209Y562167D02*
X1589183Y560723D01*
G01X1587235Y562889D02*
X1588209Y562167D01*
G01X1585286Y562889D02*
X1587235D01*
G01X1602338Y555671D02*
X1603312Y554227D01*
G01X1601851Y557836D02*
X1602338Y555671D01*
G01X1601851Y559280D02*
Y557836D01*
G01X1602338Y561445D02*
X1601851Y559280D01*
G01X1603312Y562889D02*
X1602338Y561445D01*
G01X1616954Y554949D02*
X1615980Y556393D01*
G01X1577978Y557114D02*
X1580901D01*
G01X1619168Y724712D02*
X1587910D01*
G01X1569938Y726877D02*
X1573836D01*
G01X1570425Y729043D02*
X1569938Y726877D01*
G01X1571400Y730486D02*
X1570425Y729043D01*
G01X1572374Y731208D02*
X1571400Y730486D01*
G01X1573348Y731930D02*
X1572374Y731208D01*
G01X1573836Y732651D02*
X1573348Y731930D01*
G01X1573836Y734095D02*
Y732651D01*
G01X1573348Y734817D02*
X1573836Y734095D01*
G01X1572374Y735539D02*
X1573348Y734817D01*
G01X1571400Y735539D02*
X1572374D01*
G01X1570425Y734817D02*
X1571400Y735539D01*
G01X1569938Y734095D02*
X1570425Y734817D01*
G01X1580656Y727599D02*
X1579682Y726877D01*
G01X1581144Y728321D02*
X1580656Y727599D01*
G01X1581631Y729764D02*
X1581144Y728321D01*
G01X1581631Y732651D02*
Y729764D01*
G01X1581144Y734095D02*
X1581631Y732651D01*
G01X1580656Y734817D02*
X1581144Y734095D01*
G01X1579682Y735539D02*
X1580656Y734817D01*
G01X1578708D02*
X1579682Y735539D01*
G01X1578220Y734095D02*
X1578708Y734817D01*
G01X1577733Y732651D02*
X1578220Y734095D01*
G01X1577733Y729764D02*
Y732651D01*
G01X1578220Y728321D02*
X1577733Y729764D01*
G01X1578708Y727599D02*
X1578220Y728321D01*
G01X1579682Y726877D02*
X1578708Y727599D01*
G01X1615231Y692428D02*
G03X1619168Y696365I0J3937D01*
G01X1616281Y816119D02*
X1617003Y815145D01*
G01X1615560Y816607D02*
X1616281Y816119D01*
G01X1614116Y817094D02*
X1615560Y816607D01*
G01X1611229Y817094D02*
X1614116D01*
G01X1609785Y816607D02*
X1611229Y817094D01*
G01X1609063Y816119D02*
X1609785Y816607D01*
G01X1608342Y815145D02*
X1609063Y816119D01*
G01Y814171D02*
X1608342Y815145D01*
G01X1609785Y813683D02*
X1609063Y814171D01*
G01X1611229Y813196D02*
X1609785Y813683D01*
G01X1614116Y813196D02*
X1611229D01*
G01X1615560Y813683D02*
X1614116Y813196D01*
G01X1616281Y814171D02*
X1615560Y813683D01*
G01X1617003Y815145D02*
X1616281Y814171D01*
G01Y822453D02*
X1617003Y822940D01*
G01X1609063Y831710D02*
X1609785Y832197D01*
G01X1608342Y830736D02*
X1609063Y831710D01*
G01Y829761D02*
X1608342Y830736D01*
G01X1609785Y829274D02*
X1609063Y829761D01*
G01X1611229Y828787D02*
X1609785Y829274D01*
G01X1614116Y828787D02*
X1611229D01*
G01X1615560Y829274D02*
X1614116Y828787D01*
G01X1616281Y829761D02*
X1615560Y829274D01*
G01X1617003Y830736D02*
X1616281Y829761D01*
G01Y831710D02*
X1617003Y830736D01*
G01X1615560Y832197D02*
X1616281Y831710D01*
G01X1614116Y832684D02*
X1615560Y832197D01*
G01X1612672D02*
X1614116Y832684D01*
G01X1611951Y830736D02*
X1612672Y832197D01*
G01Y829274D02*
X1611951Y830736D01*
G01X1614116Y828787D02*
X1612672Y829274D01*
G01X1614838Y805401D02*
Y809786D01*
G01X1608342Y808811D02*
X1614838Y805401D01*
G01X1617003Y808811D02*
X1608342D01*
G01X1616281Y837069D02*
X1615560Y836582D01*
G01X1617003Y838044D02*
X1616281Y837069D01*
G01Y839992D02*
X1617003Y839018D01*
G01X1615560Y840480D02*
X1616281Y839992D01*
G01X1614116Y840967D02*
X1615560Y840480D01*
G01X1612672D02*
X1614116Y840967D01*
G01X1611951Y839992D02*
X1612672Y840480D01*
G01X1611229Y839018D02*
X1611951Y839992D01*
G01X1611229Y838044D02*
Y839018D01*
G01X1611951Y837069D02*
X1611229Y838044D01*
G01X1608342Y837556D02*
X1611951Y837069D01*
G01X1608342Y840480D02*
Y837556D01*
G01X1624443Y-579293D02*
Y-323387D01*
G01Y-579293D02*
X2569325D01*
G01Y-519029D02*
X1624443D01*
G01Y-473903D02*
X2155670D01*
G01X1624443Y-428777D02*
X2569325D01*
G01X1624443Y-383651D02*
X2569325D01*
G01X1624443Y-323387D02*
X2569325D01*
G01X1619065Y234460D02*
X1618090Y233738D01*
G01X1619552Y235182D02*
X1619065Y234460D01*
G01X1620039Y236625D02*
X1619552Y235182D01*
G01X1620039Y239512D02*
Y236625D01*
G01X1619552Y240956D02*
X1620039Y239512D01*
G01X1619065Y241678D02*
X1619552Y240956D01*
G01X1618090Y242400D02*
X1619065Y241678D01*
G01X1617116D02*
X1618090Y242400D01*
G01X1616629Y240956D02*
X1617116Y241678D01*
G01Y234460D02*
X1616629Y235182D01*
G01X1618090Y233738D02*
X1617116Y234460D01*
G01X1635630Y233738D02*
Y242400D01*
G01X1631732D02*
X1635630Y233738D01*
G01X1631732D02*
Y242400D01*
G01X1641963Y238069D02*
X1639527D01*
G01X1642938Y238791D02*
X1641963Y238069D01*
G01X1643425Y239512D02*
X1642938Y238791D01*
G01X1643425Y240956D02*
Y239512D01*
G01X1642938Y241678D02*
X1643425Y240956D01*
G01X1641963Y242400D02*
X1642938Y241678D01*
G01X1639527Y242400D02*
X1641963D01*
G01X1639527Y233738D02*
Y242400D01*
G01X1625398Y235182D02*
X1626373Y233738D01*
G01X1624911Y237347D02*
X1625398Y235182D01*
G01X1624911Y238791D02*
Y237347D01*
G01X1625398Y240956D02*
X1624911Y238791D01*
G01X1626373Y242400D02*
X1625398Y240956D01*
G01X1646835Y242400D02*
X1651707D01*
G01X1655118Y238069D02*
X1659016D01*
G01Y242400D02*
Y233738D01*
G01X1655118Y242400D02*
Y233738D01*
G01X1649272Y242400D02*
Y233738D01*
G01X1620704Y333148D02*
G03X1621492Y332360I788J0D01*
G01Y334132D02*
G03X1620704Y333345I0J-788D01*
G01X1621885Y334132D02*
G03Y335707I0J788D01*
G01X1620704Y336494D02*
G03X1621492Y335707I787J0D01*
G01Y337478D02*
G03X1620704Y336691I0J-788D01*
G01X1648510Y326760D02*
X1647960Y326647D01*
G01X1648510Y322607D02*
X1649059Y322719D01*
G01X1630744Y354604D02*
X1629956D01*
G01X1634681D02*
X1633893D01*
G01X1638618D02*
X1637830D01*
G01X1642555D02*
X1641767D01*
G01X1646492D02*
X1645704D01*
G01X1650429D02*
X1649641D01*
G01X1654366D02*
X1653578D01*
G01X1658303D02*
X1657515D01*
G01X1662240D02*
X1661452D01*
G01Y354211D02*
X1662240D01*
G01X1657515D02*
X1658303D01*
G01X1653578D02*
X1654366D01*
G01X1649641D02*
X1650429D01*
G01X1645704D02*
X1646492D01*
G01X1641767D02*
X1642555D01*
G01X1637830D02*
X1638618D01*
G01X1633893D02*
X1634681D01*
G01X1629956D02*
X1630744D01*
G01Y352487D02*
X1629956D01*
G01X1634681D02*
X1633893D01*
G01X1638618D02*
X1637830D01*
G01X1642555D02*
X1641767D01*
G01X1646492D02*
X1645704D01*
G01X1650429D02*
X1649641D01*
G01X1654366D02*
X1653578D01*
G01X1658303D02*
X1657515D01*
G01X1662240D02*
X1661452D01*
G01Y352069D02*
X1662240D01*
G01X1657515D02*
X1658303D01*
G01X1653578D02*
X1654366D01*
G01X1649641D02*
X1650429D01*
G01X1645704D02*
X1646492D01*
G01X1641767D02*
X1642555D01*
G01X1637830D02*
X1638618D01*
G01X1633893D02*
X1634681D01*
G01X1629956D02*
X1630744D01*
G01Y351411D02*
X1629956D01*
G01X1634681D02*
X1633893D01*
G01X1638618D02*
X1637830D01*
G01X1642555D02*
X1641767D01*
G01X1646492D02*
X1645704D01*
G01X1650429D02*
X1649641D01*
G01X1654366D02*
X1653578D01*
G01X1658303D02*
X1657515D01*
G01X1662240D02*
X1661452D01*
G01Y351124D02*
X1662240D01*
G01X1657515D02*
X1658303D01*
G01X1653578D02*
X1654366D01*
G01X1649641D02*
X1650429D01*
G01X1645704D02*
X1646492D01*
G01X1641767D02*
X1642555D01*
G01X1637830D02*
X1638618D01*
G01X1633893D02*
X1634681D01*
G01X1629956D02*
X1630744D01*
G01Y350565D02*
X1629956D01*
G01X1634681D02*
X1633893D01*
G01X1638618D02*
X1637830D01*
G01X1642555D02*
X1641767D01*
G01X1646492D02*
X1645704D01*
G01X1650429D02*
X1649641D01*
G01X1654366D02*
X1653578D01*
G01X1658303D02*
X1657515D01*
G01X1662240D02*
X1661452D01*
G01X1672870Y350470D02*
X1627200D01*
G01X1630744Y350392D02*
X1629956D01*
G01X1634681D02*
X1633893D01*
G01X1638618D02*
X1637830D01*
G01X1642555D02*
X1641767D01*
G01X1646492D02*
X1645704D01*
G01X1650429D02*
X1649641D01*
G01X1654366D02*
X1653578D01*
G01X1658303D02*
X1657515D01*
G01X1662240D02*
X1661452D01*
G01X1630744Y350313D02*
X1629956D01*
G01X1634681D02*
X1633893D01*
G01X1638618D02*
X1637830D01*
G01X1642555D02*
X1641767D01*
G01X1646492D02*
X1645704D01*
G01X1650429D02*
X1649641D01*
G01X1654366D02*
X1653578D01*
G01X1658303D02*
X1657515D01*
G01X1662240D02*
X1661452D01*
G01X1630744Y350293D02*
X1629956D01*
G01X1634681D02*
X1633893D01*
G01X1638618D02*
X1637830D01*
G01X1642555D02*
X1641767D01*
G01X1646492D02*
X1645704D01*
G01X1650429D02*
X1649641D01*
G01X1654366D02*
X1653578D01*
G01X1658303D02*
X1657515D01*
G01X1662240D02*
X1661452D01*
G01Y350195D02*
X1662240D01*
G01X1657515D02*
X1658303D01*
G01X1653578D02*
X1654366D01*
G01X1649641D02*
X1650429D01*
G01X1645704D02*
X1646492D01*
G01X1641767D02*
X1642555D01*
G01X1637830D02*
X1638618D01*
G01X1633893D02*
X1634681D01*
G01X1629956D02*
X1630744D01*
G01X1630763Y349880D02*
X1629937D01*
G01X1634700D02*
X1633874D01*
G01X1638637D02*
X1637811D01*
G01X1642574D02*
X1641748D01*
G01X1646511D02*
X1645685D01*
G01X1650448D02*
X1649622D01*
G01X1654385D02*
X1653559D01*
G01X1658323D02*
X1657496D01*
G01X1662260D02*
X1661433D01*
G01X1628382Y348896D02*
X1625626D01*
G01X1671885Y344171D02*
X1624248D01*
G01X1630744Y344093D02*
X1629956D01*
G01X1634681D02*
X1633893D01*
G01X1638618D02*
X1637830D01*
G01X1642555D02*
X1641767D01*
G01X1646492D02*
X1645704D01*
G01X1650429D02*
X1649641D01*
G01X1654366D02*
X1653578D01*
G01X1658303D02*
X1657515D01*
G01X1662240D02*
X1661452D01*
G01X1630744Y344014D02*
X1629956D01*
G01X1634681D02*
X1633893D01*
G01X1638618D02*
X1637830D01*
G01X1642555D02*
X1641767D01*
G01X1646492D02*
X1645704D01*
G01X1650429D02*
X1649641D01*
G01X1654366D02*
X1653578D01*
G01X1658303D02*
X1657515D01*
G01X1662240D02*
X1661452D01*
G01Y339798D02*
X1662240D01*
G01X1657515D02*
X1658303D01*
G01X1653578D02*
X1654366D01*
G01X1649641D02*
X1650429D01*
G01X1645704D02*
X1646492D01*
G01X1641767D02*
X1642555D01*
G01X1637830D02*
X1638618D01*
G01X1633893D02*
X1634681D01*
G01X1629956D02*
X1630744D01*
G01X1661452Y339759D02*
X1662240D01*
G01X1657515D02*
X1658303D01*
G01X1653578D02*
X1654366D01*
G01X1649641D02*
X1650429D01*
G01X1645704D02*
X1646492D01*
G01X1641767D02*
X1642555D01*
G01X1637830D02*
X1638618D01*
G01X1633893D02*
X1634681D01*
G01X1629956D02*
X1630744D01*
G01X1661452Y339602D02*
X1662240D01*
G01X1657515D02*
X1658303D01*
G01X1653578D02*
X1654366D01*
G01X1649641D02*
X1650429D01*
G01X1645704D02*
X1646492D01*
G01X1641767D02*
X1642555D01*
G01X1637830D02*
X1638618D01*
G01X1633893D02*
X1634681D01*
G01X1629956D02*
X1630744D01*
G01X1623263Y339368D02*
X1621492D01*
G01X1624228Y338266D02*
X1625055D01*
G01Y337478D02*
X1626492D01*
G01X1625035D02*
X1621492D01*
G01X1630744Y336888D02*
X1629956D01*
G01X1634681D02*
X1633893D01*
G01X1638618D02*
X1637830D01*
G01X1642555D02*
X1641767D01*
G01X1646492D02*
X1645704D01*
G01X1650429D02*
X1649641D01*
G01X1654366D02*
X1653578D01*
G01X1658303D02*
X1657515D01*
G01X1662240D02*
X1661452D01*
G01X1630744Y336553D02*
X1629956D01*
G01X1634681D02*
X1633893D01*
G01X1638618D02*
X1637830D01*
G01X1642555D02*
X1641767D01*
G01X1646492D02*
X1645704D01*
G01X1650429D02*
X1649641D01*
G01X1654366D02*
X1653578D01*
G01X1658303D02*
X1657515D01*
G01X1662240D02*
X1661452D01*
G01X1630586Y335904D02*
X1630114D01*
G01X1634523D02*
X1634051D01*
G01X1638460D02*
X1637988D01*
G01X1642397D02*
X1641925D01*
G01X1646334D02*
X1645862D01*
G01X1650271D02*
X1649799D01*
G01X1654208D02*
X1653736D01*
G01X1658145D02*
X1657673D01*
G01X1662082D02*
X1661610D01*
G01X1630586Y335746D02*
X1630114D01*
G01X1634523D02*
X1634051D01*
G01X1638460D02*
X1637988D01*
G01X1642397D02*
X1641925D01*
G01X1646334D02*
X1645862D01*
G01X1650271D02*
X1649799D01*
G01X1654208D02*
X1653736D01*
G01X1658145D02*
X1657673D01*
G01X1662082D02*
X1661610D01*
G01X1621885Y335707D02*
X1621492D01*
G01X1630744Y335217D02*
X1629956D01*
G01X1634681D02*
X1633893D01*
G01X1638618D02*
X1637830D01*
G01X1642555D02*
X1641767D01*
G01X1646492D02*
X1645704D01*
G01X1650429D02*
X1649641D01*
G01X1654366D02*
X1653578D01*
G01X1658303D02*
X1657515D01*
G01X1662240D02*
X1661452D01*
G01Y334695D02*
X1662240D01*
G01X1657515D02*
X1658303D01*
G01X1653578D02*
X1654366D01*
G01X1649641D02*
X1650429D01*
G01X1645704D02*
X1646492D01*
G01X1641767D02*
X1642555D01*
G01X1637830D02*
X1638618D01*
G01X1633893D02*
X1634681D01*
G01X1629956D02*
X1630744D01*
G01X1621885Y334132D02*
X1621492D01*
G01X1624228Y333935D02*
X1625055D01*
G01X1661452Y333345D02*
X1666177D01*
G01X1629956D02*
X1634681D01*
G01X1650429D02*
X1645704D01*
G01X1630763Y332951D02*
X1629937D01*
G01X1634700D02*
X1633874D01*
G01X1638637D02*
X1637811D01*
G01X1642574D02*
X1641748D01*
G01X1646511D02*
X1645685D01*
G01X1650448D02*
X1649622D01*
G01X1654385D02*
X1653559D01*
G01X1658323D02*
X1657496D01*
G01X1662260D02*
X1661433D01*
G01X1629956Y332754D02*
X1624248D01*
G01X1645704D02*
X1634681D01*
G01X1661452D02*
X1650429D01*
G01X1661452Y332637D02*
X1666177D01*
G01X1629956D02*
X1634681D01*
G01X1650429D02*
X1645704D01*
G01X1625035Y332596D02*
X1624248D01*
G01X1624917Y332557D02*
X1624366D01*
G01X1621492Y332360D02*
X1674641D01*
G01X1630744Y332148D02*
X1629956D01*
G01X1634681D02*
X1633893D01*
G01X1638618D02*
X1637830D01*
G01X1642555D02*
X1641767D01*
G01X1646492D02*
X1645704D01*
G01X1650429D02*
X1649641D01*
G01X1654366D02*
X1653578D01*
G01X1658303D02*
X1657515D01*
G01X1662240D02*
X1661452D01*
G01Y331898D02*
X1662240D01*
G01X1657515D02*
X1658303D01*
G01X1653578D02*
X1654366D01*
G01X1649641D02*
X1650429D01*
G01X1645704D02*
X1646492D01*
G01X1641767D02*
X1642555D01*
G01X1637830D02*
X1638618D01*
G01X1633893D02*
X1634681D01*
G01X1629956D02*
X1630744D01*
G01X1648510Y327321D02*
X1647850Y327209D01*
G01X1648510Y322045D02*
X1649169Y322158D01*
G01X1630744Y331131D02*
X1629956D01*
G01X1634681D02*
X1633893D01*
G01X1638618D02*
X1637830D01*
G01X1642555D02*
X1641767D01*
G01X1646492D02*
X1645704D01*
G01X1650429D02*
X1649641D01*
G01X1654366D02*
X1653578D01*
G01X1658303D02*
X1657515D01*
G01X1662240D02*
X1661452D01*
G01Y330910D02*
X1662240D01*
G01X1657515D02*
X1658303D01*
G01X1653578D02*
X1654366D01*
G01X1649641D02*
X1650429D01*
G01X1645704D02*
X1646492D01*
G01X1641767D02*
X1642555D01*
G01X1637830D02*
X1638618D01*
G01X1633893D02*
X1634681D01*
G01X1629956D02*
X1630744D01*
G01Y328817D02*
X1629956D01*
G01X1634681D02*
X1633893D01*
G01X1638618D02*
X1637830D01*
G01X1642555D02*
X1641767D01*
G01X1646492D02*
X1645704D01*
G01X1650429D02*
X1649641D01*
G01X1654366D02*
X1653578D01*
G01X1658303D02*
X1657515D01*
G01X1662240D02*
X1661452D01*
G01X1630744Y328620D02*
X1629956D01*
G01X1634681D02*
X1633893D01*
G01X1638618D02*
X1637830D01*
G01X1642555D02*
X1641767D01*
G01X1646492D02*
X1645704D01*
G01X1650429D02*
X1649641D01*
G01X1654366D02*
X1653578D01*
G01X1658303D02*
X1657515D01*
G01X1662240D02*
X1661452D01*
G01X1642355Y327321D02*
X1643014D01*
G01X1638618D02*
X1639277D01*
G01X1659171Y325637D02*
X1659610D01*
G01X1657412D02*
X1657852D01*
G01X1656313D02*
X1656863D01*
G01X1654225D02*
X1654664D01*
G01X1652466D02*
X1652906D01*
G01X1651367D02*
X1651917D01*
G01X1643893D02*
X1645652D01*
G01X1639277Y325188D02*
X1642355D01*
G01X1645652D02*
X1643893D01*
G01X1652686D02*
X1652466D01*
G01X1654445D02*
X1654115D01*
G01X1657632D02*
X1657412D01*
G01X1659390D02*
X1659061D01*
G01X1642355Y324515D02*
X1639277D01*
G01X1643893Y324290D02*
X1645652D01*
G01Y323841D02*
X1643893D01*
G01X1639277Y322045D02*
X1638618D01*
G01X1643014D02*
X1642355D01*
G01X1651917D02*
X1651367D01*
G01X1653675D02*
X1653126D01*
G01X1655434D02*
X1654884D01*
G01X1658621D02*
X1658072D01*
G01X1656863D02*
X1656313D01*
G01X1660380D02*
X1659830D01*
G01X1649059Y326647D02*
X1648510Y326760D01*
G01X1647960Y322719D02*
X1648510Y322607D01*
G01X1649169Y327209D02*
X1648510Y327321D01*
G01X1647850Y322158D02*
X1648510Y322045D01*
G01X1659610Y325637D02*
X1659940Y325525D01*
G01X1657852Y325637D02*
X1658181Y325525D01*
G01X1654664Y325637D02*
X1654994Y325525D01*
G01X1652906Y325637D02*
X1653236Y325525D01*
G01X1658841D02*
X1659171Y325637D01*
G01X1657412Y325188D02*
X1657082Y325076D01*
G01Y325525D02*
X1657412Y325637D01*
G01X1653895Y325525D02*
X1654225Y325637D01*
G01X1652466Y325188D02*
X1652136Y325076D01*
G01Y325525D02*
X1652466Y325637D01*
G01X1659061Y325188D02*
X1658841Y325076D01*
G01X1649718Y326872D02*
X1649169Y327209D01*
G01X1659610Y325076D02*
X1659390Y325188D01*
G01X1657852Y325076D02*
X1657632Y325188D01*
G01X1654664Y325076D02*
X1654445Y325188D01*
G01X1652906Y325076D02*
X1652686Y325188D01*
G01X1654115D02*
X1653895Y325076D01*
G01X1649169Y322158D02*
X1649718Y322494D01*
G01X1647850Y327209D02*
X1647301Y326872D01*
G01X1649059Y322719D02*
X1649389Y322943D01*
G01X1659940Y325525D02*
X1660160Y325300D01*
G01X1659720Y324964D02*
X1659610Y325076D01*
G01X1658181Y325525D02*
X1658511Y325188D01*
G01X1657962Y324964D02*
X1657852Y325076D01*
G01X1661433Y349880D02*
X1660842Y350470D01*
G01X1657496Y349880D02*
X1656905Y350470D01*
G01X1653559Y349880D02*
X1652968Y350470D01*
G01X1649622Y349880D02*
X1649031Y350470D01*
G01X1645685Y349880D02*
X1645094Y350470D01*
G01X1662260Y332951D02*
X1662850Y332360D01*
G01X1641748Y349880D02*
X1641157Y350470D01*
G01X1658323Y332951D02*
X1658913Y332360D01*
G01X1637811Y349880D02*
X1637220Y350470D01*
G01X1654385Y332951D02*
X1654976Y332360D01*
G01X1633874Y349880D02*
X1633283Y350470D01*
G01X1650448Y332951D02*
X1651039Y332360D01*
G01X1629937Y349880D02*
X1629346Y350470D01*
G01X1646511Y332951D02*
X1647102Y332360D01*
G01X1649389Y326423D02*
X1649059Y326647D01*
G01X1647630Y322943D02*
X1647960Y322719D01*
G01X1647301Y322494D02*
X1647850Y322158D01*
G01X1647960Y326647D02*
X1647630Y326423D01*
G01X1660842Y332360D02*
X1661433Y332951D01*
G01X1656905Y332360D02*
X1657496Y332951D01*
G01X1658841Y325076D02*
X1658731Y324964D01*
G01X1658511Y325188D02*
X1658841Y325525D01*
G01X1657082Y325076D02*
X1656863Y324851D01*
G01Y325300D02*
X1657082Y325525D01*
G01X1653895Y325076D02*
X1653785Y324964D01*
G01X1653565Y325188D02*
X1653895Y325525D01*
G01X1649718Y322494D02*
X1650048Y322831D01*
G01X1652136Y325076D02*
X1651917Y324851D01*
G01Y325300D02*
X1652136Y325525D01*
G01X1649828Y325749D02*
X1649389Y326423D01*
G01X1654994Y325525D02*
X1655214Y325300D01*
G01X1654774Y324964D02*
X1654664Y325076D01*
G01X1653236Y325525D02*
X1653565Y325188D01*
G01X1653016Y324964D02*
X1652906Y325076D01*
G01X1650048Y326535D02*
X1649718Y326872D01*
G01X1646971Y322831D02*
X1647301Y322494D01*
G01X1642574Y332951D02*
X1643165Y332360D01*
G01X1638637Y332951D02*
X1639228Y332360D01*
G01X1634700Y332951D02*
X1635291Y332360D01*
G01X1630763Y332951D02*
X1631354Y332360D01*
G01X1624366Y332557D02*
X1624248Y332675D01*
G01X1652968Y332360D02*
X1653559Y332951D01*
G01X1649031Y332360D02*
X1649622Y332951D01*
G01X1645094Y332360D02*
X1645685Y332951D01*
G01X1662850Y350470D02*
X1662260Y349880D01*
G01X1641157Y332360D02*
X1641748Y332951D01*
G01X1658913Y350470D02*
X1658323Y349880D01*
G01X1637220Y332360D02*
X1637811Y332951D01*
G01X1654976Y350470D02*
X1654385Y349880D01*
G01X1633283Y332360D02*
X1633874Y332951D01*
G01X1651039Y350470D02*
X1650448Y349880D01*
G01X1629346Y332360D02*
X1629937Y332951D01*
G01X1647102Y350470D02*
X1646511Y349880D01*
G01X1626019Y332754D02*
X1625626Y332360D01*
G01X1643165Y350470D02*
X1642574Y349880D01*
G01X1625035Y332675D02*
X1624917Y332557D01*
G01X1624248Y332754D02*
X1623854Y332360D01*
G01X1639228Y350470D02*
X1638637Y349880D01*
G01X1647301Y326872D02*
X1646971Y326535D01*
G01X1649389Y322943D02*
X1649828Y323617D01*
G01X1647630Y326423D02*
X1647191Y325749D01*
G01X1658731Y324964D02*
X1658621Y324739D01*
G01X1649938Y325076D02*
X1649828Y325749D01*
G01X1661452Y336553D02*
X1661610Y335746D01*
G01X1657515Y336553D02*
X1657673Y335746D01*
G01X1653578Y336553D02*
X1653736Y335746D01*
G01X1649641Y336553D02*
X1649799Y335746D01*
G01X1650488Y325188D02*
X1650378Y325749D01*
G01X1661452Y336691D02*
X1661610Y335904D01*
G01X1657515Y336691D02*
X1657673Y335904D01*
G01X1653578Y336691D02*
X1653736Y335904D01*
G01X1649641Y336691D02*
X1649799Y335904D01*
G01X1650378Y325749D02*
X1650268Y326086D01*
G01X1646641Y323617D02*
X1646751Y323280D01*
G01X1660160Y325300D02*
X1660380Y324739D01*
G01X1655214Y325300D02*
X1655434Y324739D01*
G01X1659830D02*
X1659720Y324964D01*
G01X1658072Y324739D02*
X1657962Y324964D01*
G01X1654884Y324739D02*
X1654774Y324964D01*
G01X1653126Y324739D02*
X1653016Y324964D01*
G01X1650268Y326086D02*
X1650048Y326535D01*
G01X1646751Y323280D02*
X1646971Y322831D01*
G01X1647191Y323617D02*
X1647630Y322943D01*
G01X1621492Y337449D02*
X1623263Y334919D01*
G01X1635291Y350470D02*
X1634700Y349880D01*
G01X1631354Y350470D02*
X1630763Y349880D01*
G01X1627200Y350470D02*
X1623263Y346533D01*
G01X1653785Y324964D02*
X1653675Y324739D01*
G01X1650048Y322831D02*
X1650268Y323280D01*
G01X1646971Y326535D02*
X1646751Y326086D01*
G01X1650268Y323280D02*
X1650378Y323617D01*
G01X1646751Y326086D02*
X1646641Y325749D01*
G01X1662082Y335904D02*
X1662240Y336691D01*
G01X1658145Y335904D02*
X1658303Y336691D01*
G01X1654208Y335904D02*
X1654366Y336691D01*
G01X1650271Y335904D02*
X1650429Y336691D01*
G01X1650378Y323617D02*
X1650488Y324178D01*
G01X1662240Y336553D02*
X1662082Y335746D01*
G01X1658303Y336553D02*
X1658145Y335746D01*
G01X1654366Y336553D02*
X1654208Y335746D01*
G01X1650429Y336553D02*
X1650271Y335746D01*
G01X1649828Y323617D02*
X1649938Y324290D01*
G01X1662240Y332951D02*
Y328620D01*
G01Y344171D02*
Y334695D01*
G01Y354604D02*
Y349880D01*
G01X1661452Y344171D02*
Y328620D01*
G01Y354604D02*
Y349880D01*
G01X1660380Y324739D02*
Y322045D01*
G01X1659830D02*
Y324739D01*
G01X1658621D02*
Y322045D01*
G01X1658303Y332951D02*
Y328620D01*
G01Y344171D02*
Y334695D01*
G01Y354604D02*
Y349880D01*
G01X1658072Y322045D02*
Y324739D01*
G01X1657515Y332951D02*
Y328620D01*
G01Y344171D02*
Y334695D01*
G01Y354604D02*
Y349880D01*
G01X1656863Y324851D02*
Y322045D01*
G01Y325637D02*
Y325300D01*
G01X1656313Y322045D02*
Y325637D01*
G01X1655434Y324739D02*
Y322045D01*
G01X1654884D02*
Y324739D01*
G01X1654366Y332951D02*
Y328620D01*
G01Y344171D02*
Y334695D01*
G01Y354604D02*
Y349880D01*
G01X1653675Y324739D02*
Y322045D01*
G01X1653578Y332951D02*
Y328620D01*
G01Y344171D02*
Y334695D01*
G01Y354604D02*
Y349880D01*
G01X1653126Y322045D02*
Y324739D01*
G01X1651917Y324851D02*
Y322045D01*
G01Y325637D02*
Y325300D01*
G01X1651367Y322045D02*
Y325637D01*
G01X1647081Y324290D02*
X1647191Y323617D01*
G01X1645704Y336553D02*
X1645862Y335746D01*
G01X1641767Y336553D02*
X1641925Y335746D01*
G01X1637830Y336553D02*
X1637988Y335746D01*
G01X1633893Y336553D02*
X1634051Y335746D01*
G01X1629956Y336553D02*
X1630114Y335746D01*
G01X1646531Y324178D02*
X1646641Y323617D01*
G01X1645704Y336691D02*
X1645862Y335904D01*
G01X1641767Y336691D02*
X1641925Y335904D01*
G01X1637830Y336691D02*
X1637988Y335904D01*
G01X1633893Y336691D02*
X1634051Y335904D01*
G01X1629956Y336691D02*
X1630114Y335904D01*
G01X1625448Y332360D02*
X1625055Y333935D01*
G01X1624228D02*
X1623834Y332360D01*
G01X1646334Y335904D02*
X1646492Y336691D01*
G01X1642397Y335904D02*
X1642555Y336691D01*
G01X1638460Y335904D02*
X1638618Y336691D01*
G01X1634523Y335904D02*
X1634681Y336691D01*
G01X1630586Y335904D02*
X1630744Y336691D01*
G01X1646641Y325749D02*
X1646531Y325188D01*
G01X1646492Y336553D02*
X1646334Y335746D01*
G01X1642555Y336553D02*
X1642397Y335746D01*
G01X1638618Y336553D02*
X1638460Y335746D01*
G01X1634681Y336553D02*
X1634523Y335746D01*
G01X1630744Y336553D02*
X1630586Y335746D01*
G01X1647191Y325749D02*
X1647081Y325076D01*
G01X1650488Y324178D02*
Y325188D01*
G01X1650429Y328620D02*
Y344171D01*
G01Y354604D02*
Y349880D01*
G01X1649938Y324290D02*
Y325076D01*
G01X1649641Y332951D02*
Y328620D01*
G01Y344171D02*
Y334695D01*
G01Y354604D02*
Y349880D01*
G01X1647081Y325076D02*
Y324290D01*
G01X1646531Y325188D02*
Y324178D01*
G01X1646492Y332951D02*
Y328620D01*
G01Y344171D02*
Y334695D01*
G01Y354604D02*
Y349880D01*
G01X1645704Y344171D02*
Y328620D01*
G01Y354604D02*
Y349880D01*
G01X1645652Y324290D02*
Y323841D01*
G01Y325637D02*
Y325188D01*
G01X1643893Y323841D02*
Y324290D01*
G01Y325188D02*
Y325637D01*
G01X1643014Y327321D02*
Y322045D01*
G01X1642555Y332951D02*
Y328620D01*
G01Y344171D02*
Y334695D01*
G01Y354604D02*
Y349880D01*
G01X1642355Y325188D02*
Y327321D01*
G01Y322045D02*
Y324515D01*
G01X1641767Y332951D02*
Y328620D01*
G01Y344171D02*
Y334695D01*
G01Y354604D02*
Y349880D01*
G01X1639277Y324515D02*
Y322045D01*
G01Y327321D02*
Y325188D01*
G01X1638618Y322045D02*
Y327321D01*
G01Y332951D02*
Y328620D01*
G01Y344171D02*
Y334695D01*
G01Y354604D02*
Y349880D01*
G01X1637830Y332951D02*
Y328620D01*
G01Y344171D02*
Y334695D01*
G01Y354604D02*
Y349880D01*
G01X1634681Y344171D02*
Y328620D01*
G01Y354604D02*
Y349880D01*
G01X1633893Y332951D02*
Y328620D01*
G01Y344171D02*
Y334695D01*
G01Y354604D02*
Y349880D01*
G01X1630744Y332951D02*
Y328620D01*
G01Y344171D02*
Y334695D01*
G01Y354604D02*
Y349880D01*
G01X1629956Y344171D02*
Y328620D01*
G01Y354604D02*
Y349880D01*
G01X1628382Y332360D02*
Y348896D01*
G01X1627988Y332360D02*
Y344171D01*
G01X1626492Y337478D02*
Y332360D01*
G01X1626019Y344171D02*
Y332754D01*
G01X1625055Y338266D02*
Y337478D01*
G01X1625035Y338266D02*
Y332360D01*
G01X1624248Y344171D02*
Y332360D01*
G01X1624228Y337478D02*
Y338266D01*
G01X1623263Y332360D02*
Y346533D01*
G01X1621492Y339368D02*
Y337449D01*
G01X1620704Y333345D02*
Y333148D01*
G01Y336691D02*
Y336494D01*
G01X1618539Y366219D02*
X1677594D01*
G01X1638376Y412085D02*
X1635940D01*
G01X1639350Y412806D02*
X1638376Y412085D01*
G01X1639837Y413528D02*
X1639350Y412806D01*
G01X1639837Y414972D02*
Y413528D01*
G01X1639350Y415694D02*
X1639837Y414972D01*
G01X1638376Y416415D02*
X1639350Y415694D01*
G01X1635940Y416415D02*
X1638376D01*
G01X1635940Y407754D02*
Y416415D01*
G01X1645684D02*
X1648120Y407754D01*
G01X1643248D02*
X1645684Y416415D01*
G01X1652017Y408476D02*
X1651043Y409919D01*
G01X1652992Y407754D02*
X1652017Y408476D01*
G01X1653966Y407754D02*
X1652992D01*
G01X1654941Y408476D02*
X1653966Y407754D01*
G01X1655428Y409198D02*
X1654941Y408476D01*
G01Y415694D02*
X1655428Y414972D01*
G01X1653966Y416415D02*
X1654941Y415694D01*
G01X1652992Y416415D02*
X1653966D01*
G01X1652017Y415694D02*
X1652992Y416415D01*
G01X1617426Y412085D02*
X1616939Y409919D01*
G01Y414250D02*
X1617426Y412085D01*
G01X1651043Y414250D02*
X1652017Y415694D01*
G01X1650556Y412085D02*
X1651043Y414250D01*
G01Y409919D02*
X1650556Y412085D01*
G01X1659326Y416415D02*
X1663223D01*
G01X1659326Y407754D02*
Y416415D01*
G01X1663223Y407754D02*
X1659326D01*
G01X1627657Y416415D02*
X1632529D01*
G01X1659326Y412085D02*
X1661762D01*
G01X1644222Y410641D02*
X1647145D01*
G01X1638376Y412085D02*
X1639837Y407754D01*
G01X1630093Y416415D02*
Y407754D01*
G01X1619877Y562167D02*
X1620852Y560723D01*
G01X1618903Y562889D02*
X1619877Y562167D01*
G01X1617929Y562889D02*
X1618903D01*
G01X1616954Y562167D02*
X1617929Y562889D01*
G01X1616467Y561445D02*
X1616954Y562167D01*
G01X1620852Y556393D02*
X1620365Y555671D01*
G01X1621339Y558558D02*
X1620852Y556393D01*
G01Y560723D02*
X1621339Y558558D01*
G01X1658854Y562167D02*
X1659341Y561445D01*
G01X1657879Y562889D02*
X1658854Y562167D01*
G01X1656905Y562889D02*
X1657879D01*
G01X1655931Y562167D02*
X1656905Y562889D01*
G01X1655443Y561445D02*
X1655931Y562167D01*
G01X1654956Y560723D02*
X1655443Y561445D01*
G01X1654469Y558558D02*
X1654956Y560723D01*
G01Y556393D02*
X1654469Y558558D01*
G01X1655931Y554949D02*
X1654956Y556393D01*
G01X1642289Y558558D02*
X1639853D01*
G01X1643263Y559280D02*
X1642289Y558558D01*
G01X1643750Y560002D02*
X1643263Y559280D01*
G01X1643750Y561445D02*
Y560002D01*
G01X1643263Y562167D02*
X1643750Y561445D01*
G01X1642289Y562889D02*
X1643263Y562167D01*
G01X1639853Y562889D02*
X1642289D01*
G01X1639853Y554227D02*
Y562889D01*
G01X1649597D02*
X1652033Y554227D01*
G01X1647161D02*
X1649597Y562889D01*
G01X1663239D02*
X1667136D01*
G01X1663239Y554227D02*
Y562889D01*
G01X1667136Y554227D02*
X1663239D01*
G01X1617929D02*
X1616954Y554949D01*
G01X1618903Y554227D02*
X1617929D01*
G01X1619877Y554949D02*
X1618903Y554227D01*
G01X1620365Y555671D02*
X1619877Y554949D01*
G01X1656905Y554227D02*
X1655931Y554949D01*
G01X1657879Y554227D02*
X1656905D01*
G01X1658854Y554949D02*
X1657879Y554227D01*
G01X1659341Y555671D02*
X1658854Y554949D01*
G01X1631570Y562889D02*
X1636442D01*
G01X1663239Y558558D02*
X1665675D01*
G01X1648135Y557114D02*
X1651058D01*
G01X1634006Y562889D02*
Y554227D01*
G01X1642289Y558558D02*
X1643750Y554227D01*
G01X1619168Y724712D02*
Y799121D01*
G01X1637869Y715263D02*
G03X1639050I590J0D01*
G01Y708964D02*
G03X1637869I-590J0D01*
G01X1635901D02*
G03X1634720I-591J0D01*
G01Y715263D02*
G03X1635901I590J0D01*
G01X1637869D02*
G03X1639050I590J0D01*
G01Y708964D02*
G03X1637869I-590J0D01*
G01X1635901D02*
G03X1634720I-591J0D01*
G01Y715263D02*
G03X1635901I590J0D01*
G01X1623105Y724712D02*
G03X1619168Y720775I0J-3937D01*
G01X1638181Y713996D02*
X1638140Y713987D01*
G01X1623105Y724712D02*
X1682161D01*
G01X1637279Y715263D02*
X1639641D01*
G01X1634129D02*
X1636491D01*
G01X1634720D02*
X1633932D01*
G01X1634720D02*
X1633932D01*
G01X1637869D02*
X1635901D01*
G01X1637869D02*
X1635901D01*
G01X1639838D02*
X1639050D01*
G01X1639838D02*
X1639050D01*
G01X1639838Y714279D02*
X1633932D01*
G01X1638870Y714205D02*
X1638919D01*
G01X1638706D02*
X1638755D01*
G01X1638427D02*
X1638501D01*
G01X1638312D02*
X1638361D01*
G01X1637943D02*
X1638140D01*
G01X1638148Y714163D02*
X1637992D01*
G01X1633932Y714082D02*
X1639838D01*
G01X1637992Y714038D02*
X1638148D01*
G01X1638140Y713987D02*
X1637992D01*
G01X1638919Y713811D02*
X1638870D01*
G01X1638755D02*
X1638681D01*
G01X1638476D02*
X1638427D01*
G01X1638361D02*
X1638312D01*
G01X1637992D02*
X1637943D01*
G01X1636491Y713688D02*
X1634129D01*
G01X1639641D02*
X1637279D01*
G01X1636491Y710539D02*
X1634129D01*
G01X1639641D02*
X1637279D01*
G01X1633932Y710145D02*
X1639838D01*
G01Y709948D02*
X1633932D01*
G01X1639050Y708964D02*
X1639838D01*
G01X1639050D02*
X1639838D01*
G01X1637279D02*
X1639641D01*
G01X1635901D02*
X1637869D01*
G01X1635901D02*
X1637869D01*
G01X1634129D02*
X1636491D01*
G01X1633932D02*
X1634720D01*
G01X1633932D02*
X1634720D01*
G01X1638140Y714205D02*
X1638181Y714197D01*
G01X1638173Y714155D02*
X1638148Y714163D01*
G01X1638181Y714197D02*
X1638214Y714172D01*
G01X1638148Y714038D02*
X1638173Y714046D01*
G01X1638189Y714138D02*
X1638173Y714155D01*
G01X1638214Y714172D02*
X1638238Y714138D01*
G01X1638214Y714021D02*
X1638181Y713996D01*
G01X1638238Y714138D02*
X1638246Y714113D01*
G01X1638197D02*
X1638189Y714138D01*
G01X1638681Y713811D02*
X1638476Y714155D01*
G01X1638501Y714205D02*
X1638706Y713870D01*
G01X1638173Y714046D02*
X1638189Y714063D01*
G01X1638870Y714138D02*
X1638821Y714079D01*
G01Y714146D02*
X1638870Y714205D01*
G01X1638238Y714054D02*
X1638214Y714021D01*
G01X1638246Y714079D02*
X1638238Y714054D01*
G01X1638189Y714063D02*
X1638197Y714088D01*
G01X1639838Y708964D02*
Y715263D01*
G01Y708964D02*
Y715263D01*
G01X1639641Y708964D02*
Y710539D01*
G01Y715263D02*
Y713688D01*
G01X1638919Y714205D02*
Y713811D01*
G01X1638870D02*
Y714138D01*
G01X1638821Y714079D02*
Y714146D01*
G01X1638755Y714205D02*
Y713811D01*
G01X1638706Y713870D02*
Y714205D01*
G01X1638476Y714155D02*
Y713811D01*
G01X1638427D02*
Y714205D01*
G01X1638361D02*
Y713811D01*
G01X1638312D02*
Y714205D01*
G01X1638246Y714113D02*
Y714079D01*
G01X1638197Y714088D02*
Y714113D01*
G01X1637992Y714163D02*
Y714038D01*
G01Y713987D02*
Y713811D01*
G01X1637943D02*
Y714205D01*
G01X1637279Y713688D02*
Y715263D01*
G01Y710539D02*
Y708964D01*
G01X1636491D02*
Y710539D01*
G01Y715263D02*
Y713688D01*
G01X1634129D02*
Y715263D01*
G01Y710539D02*
Y708964D01*
G01X1633932D02*
Y715263D01*
G01D02*
Y708964D01*
G01X1619168Y696365D02*
Y720775D01*
G01X1617003Y822453D02*
X1616281D01*
G01X1617003Y822940D02*
Y822453D01*
G01Y839018D02*
Y838044D01*
G01X1665349Y235182D02*
X1664375Y233738D01*
G01X1665836Y237347D02*
X1665349Y235182D01*
G01X1665836Y238791D02*
Y237347D01*
G01X1665349Y240956D02*
X1665836Y238791D01*
G01X1664375Y242400D02*
X1665349Y240956D01*
G01X1680744Y290628D02*
Y332360D01*
G01X1675429Y336691D02*
G03X1674641Y337478I-787J0D01*
G01Y335707D02*
G03X1675429Y336494I0J788D01*
G01X1674248Y335707D02*
G03Y334132I0J-787D01*
G01X1675429Y333345D02*
G03X1674641Y334132I-787J0D01*
G01Y332360D02*
G03X1675429Y333148I0J788D01*
G01X1681531Y337872D02*
G03X1685468Y333935I3937J0D01*
G01X1666334Y355707D02*
X1666252Y355690D01*
G01X1664874Y355707D02*
X1664776D01*
G01X1665202D02*
X1665104D01*
G01X1665760D02*
X1665613D01*
G01X1665990D02*
X1665891D01*
G01X1666728D02*
X1666334D01*
G01X1666318Y355623D02*
X1666630D01*
G01Y355372D02*
X1666318D01*
G01X1666334Y355271D02*
X1666630D01*
G01X1665662Y354919D02*
X1665760D01*
G01X1665891D02*
X1665990D01*
G01X1666630D02*
X1666728D01*
G01X1664776D02*
X1664874D01*
G01X1665104D02*
X1665252D01*
G01X1666177Y354604D02*
X1665389D01*
G01Y354211D02*
X1666177D01*
G01Y352487D02*
X1665389D01*
G01Y352069D02*
X1666177D01*
G01Y351411D02*
X1665389D01*
G01Y351124D02*
X1666177D01*
G01Y350565D02*
X1665389D01*
G01X1666177Y350392D02*
X1665389D01*
G01X1666177Y350313D02*
X1665389D01*
G01X1666177Y350293D02*
X1665389D01*
G01X1672082Y350274D02*
X1667752D01*
G01X1665389Y350195D02*
X1666177D01*
G01X1666197Y349880D02*
X1665370D01*
G01X1672870Y348896D02*
X1667752D01*
G01X1666177Y344093D02*
X1665389D01*
G01X1666177Y344014D02*
X1665389D01*
G01Y339798D02*
X1666177D01*
G01X1665389Y339759D02*
X1666177D01*
G01X1665389Y339602D02*
X1666177D01*
G01X1674641Y339368D02*
X1672870D01*
G01X1671078Y338266D02*
X1671905D01*
G01X1671078Y337478D02*
X1669641D01*
G01X1674641D02*
X1671098D01*
G01X1666177Y336888D02*
X1665389D01*
G01X1666177Y336553D02*
X1665389D01*
G01X1666019Y335904D02*
X1665547D01*
G01X1666019Y335746D02*
X1665547D01*
G01X1674641Y335707D02*
X1674248D01*
G01X1666177Y335217D02*
X1665389D01*
G01Y334695D02*
X1666177D01*
G01X1674248Y334132D02*
X1674641D01*
G01X1671078Y333935D02*
X1671905D01*
G01X1736846D02*
X1685468D01*
G01X1666197Y332951D02*
X1665370D01*
G01X1671885Y332754D02*
X1666177D01*
G01X1671885Y332596D02*
X1671098D01*
G01X1671767Y332557D02*
X1671216D01*
G01X1666177Y332148D02*
X1665389D01*
G01Y331898D02*
X1666177D01*
G01X1666252Y355288D02*
X1666334Y355271D01*
G01X1666177Y331131D02*
X1665389D01*
G01Y330910D02*
X1666177D01*
G01Y328817D02*
X1665389D01*
G01X1666177Y328620D02*
X1665389D01*
G01X1666318Y355372D02*
X1666269Y355388D01*
G01D02*
X1666236Y355422D01*
G01X1665370Y349880D02*
X1664779Y350470D01*
G01X1666187Y355338D02*
X1666252Y355288D01*
G01X1666269Y355606D02*
X1666318Y355623D01*
G01X1666137Y355405D02*
X1666187Y355338D01*
G01X1664973Y355589D02*
X1664874Y355707D01*
G01Y355573D02*
X1664973Y355455D01*
G01X1671885Y332754D02*
X1672279Y332360D01*
G01X1671216Y332557D02*
X1671098Y332675D01*
G01X1670508Y332360D02*
X1670114Y332754D01*
G01X1666197Y332951D02*
X1666787Y332360D01*
G01X1666252Y355690D02*
X1666187Y355640D01*
G01X1671885Y332675D02*
X1671767Y332557D01*
G01X1664779Y332360D02*
X1665370Y332951D01*
G01X1672299Y332360D02*
X1671905Y333935D01*
G01X1666236Y355422D02*
X1666219Y355472D01*
G01X1666121Y355455D02*
X1666137Y355405D01*
G01X1666787Y350470D02*
X1666197Y349880D01*
G01X1666236Y355573D02*
X1666269Y355606D01*
G01X1666187Y355640D02*
X1666137Y355573D01*
G01X1674641Y337449D02*
X1672870Y334919D01*
G01X1681531Y362282D02*
Y337872D01*
G01X1665389Y336553D02*
X1665547Y335746D01*
G01X1665389Y336691D02*
X1665547Y335904D01*
G01X1665613Y355707D02*
X1665202Y355037D01*
G01X1665252Y354919D02*
X1665662Y355606D01*
G01X1666219Y355522D02*
X1666236Y355573D01*
G01X1666137D02*
X1666121Y355522D01*
G01X1671078Y333935D02*
X1670685Y332360D01*
G01X1666019Y335904D02*
X1666177Y336691D01*
G01Y336553D02*
X1666019Y335746D01*
G01X1675429Y333345D02*
Y333148D01*
G01Y336691D02*
Y336494D01*
G01X1674641Y339368D02*
Y337449D01*
G01X1672870Y350470D02*
Y332360D01*
G01X1672082Y350470D02*
Y350274D01*
G01X1671905Y338266D02*
Y337478D01*
G01X1671885Y332360D02*
Y344171D01*
G01X1671098Y338266D02*
Y332360D01*
G01X1671078Y337478D02*
Y338266D01*
G01X1670114Y344171D02*
Y332754D01*
G01X1669641Y337478D02*
Y332360D01*
G01X1668145D02*
Y344171D01*
G01X1667752Y348896D02*
Y332360D01*
G01Y350470D02*
Y350274D01*
G01X1666728Y354919D02*
Y355707D01*
G01X1666630Y355623D02*
Y355372D01*
G01Y355271D02*
Y354919D01*
G01X1666219Y355472D02*
Y355522D01*
G01X1666177Y344171D02*
Y328620D01*
G01Y354604D02*
Y349880D01*
G01X1666121Y355522D02*
Y355455D01*
G01X1665990Y354919D02*
Y355707D01*
G01X1665891D02*
Y354919D01*
G01X1665760D02*
Y355707D01*
G01X1665662Y355606D02*
Y354919D01*
G01X1665389Y332951D02*
Y328620D01*
G01Y344171D02*
Y334695D01*
G01Y354604D02*
Y349880D01*
G01X1665202Y355037D02*
Y355707D01*
G01X1665104D02*
Y354919D01*
G01X1664973Y355455D02*
Y355589D01*
G01X1664874Y354919D02*
Y355573D01*
G01X1664776Y355707D02*
Y354919D01*
G01X1681531Y362282D02*
G03X1677594Y366219I-3937J0D01*
G01X1676865Y416415D02*
X1679301Y407754D01*
G01X1674429D02*
X1676865Y416415D01*
G01X1700251D02*
X1702687Y407754D01*
G01X1697815D02*
X1700251Y416415D01*
G01X1706097Y407754D02*
X1709995D01*
G01X1706097Y416415D02*
Y407754D01*
G01X1682224Y416415D02*
X1687096D01*
G01X1698789Y410641D02*
X1701712D01*
G01X1675403D02*
X1678327D01*
G01X1684660Y416415D02*
Y407754D01*
G01X1710010Y554227D02*
X1713908D01*
G01X1710010Y562889D02*
Y554227D01*
G01X1680778Y562889D02*
X1683214Y554227D01*
G01X1678342D02*
X1680778Y562889D01*
G01X1704164D02*
X1706600Y554227D01*
G01X1701728D02*
X1704164Y562889D01*
G01X1686137D02*
X1691009D01*
G01X1702702Y557114D02*
X1705625D01*
G01X1679316D02*
X1682240D01*
G01X1688573Y562889D02*
Y554227D01*
G01X1686098Y724712D02*
Y799121D01*
G01Y720775D02*
G03X1682161Y724712I-3937J0D01*
G01X1686098Y696365D02*
G03X1690035Y692428I3937J0D01*
G01X1741413D02*
X1690035D01*
G01X1686098Y720775D02*
Y696365D01*
G01X1683210Y805888D02*
X1682489Y805401D01*
G01X1683932Y806863D02*
X1683210Y805888D01*
G01X1683932Y807837D02*
Y806863D01*
G01X1683210Y808811D02*
X1683932Y807837D01*
G01X1682489Y809298D02*
X1683210Y808811D01*
G01X1681045Y809786D02*
X1682489Y809298D01*
G01X1679601D02*
X1681045Y809786D01*
G01X1678880Y808811D02*
X1679601Y809298D01*
G01X1678158Y807837D02*
X1678880Y808811D01*
G01X1678158Y806863D02*
Y807837D01*
G01X1678880Y805888D02*
X1678158Y806863D01*
G01X1675271Y806375D02*
X1678880Y805888D01*
G01X1675271Y809298D02*
Y806375D01*
G01X1683210Y822453D02*
X1683932Y822940D01*
G01Y822453D02*
X1683210D01*
G01X1683932Y822940D02*
Y822453D01*
G01X1675993Y831710D02*
X1676714Y832197D01*
G01X1675271Y830736D02*
X1675993Y831710D01*
G01Y829761D02*
X1675271Y830736D01*
G01X1676714Y829274D02*
X1675993Y829761D01*
G01X1678158Y828787D02*
X1676714Y829274D01*
G01X1681045Y828787D02*
X1678158D01*
G01X1682489Y829274D02*
X1681045Y828787D01*
G01X1683210Y829761D02*
X1682489Y829274D01*
G01X1683932Y830736D02*
X1683210Y829761D01*
G01Y831710D02*
X1683932Y830736D01*
G01X1682489Y832197D02*
X1683210Y831710D01*
G01X1681045Y832684D02*
X1682489Y832197D01*
G01X1679601D02*
X1681045Y832684D01*
G01X1678880Y830736D02*
X1679601Y832197D01*
G01Y829274D02*
X1678880Y830736D01*
G01X1681045Y828787D02*
X1679601Y829274D01*
G01X1675271Y817094D02*
Y813196D01*
G01X1676714Y816607D02*
X1675271Y817094D01*
G01X1678158Y816119D02*
X1676714Y816607D01*
G01X1680323Y815632D02*
X1678158Y816119D01*
G01X1683932Y815145D02*
X1680323Y815632D01*
G01X1683210Y837069D02*
X1682489Y836582D01*
G01X1683932Y838044D02*
X1683210Y837069D01*
G01X1683932Y839018D02*
Y838044D01*
G01X1683210Y839992D02*
X1683932Y839018D01*
G01X1682489Y840480D02*
X1683210Y839992D01*
G01X1681045Y840967D02*
X1682489Y840480D01*
G01X1679601D02*
X1681045Y840967D01*
G01X1678880Y839992D02*
X1679601Y840480D01*
G01X1678158Y839018D02*
X1678880Y839992D01*
G01X1678158Y838044D02*
Y839018D01*
G01X1678880Y837069D02*
X1678158Y838044D01*
G01X1675271Y837556D02*
X1678880Y837069D01*
G01X1675271Y840480D02*
Y837556D01*
G01X1724337Y-618663D02*
Y-637600D01*
G01X1761551Y314250D02*
G03I-5020J0D01*
G01X1768342D02*
G03I-11811J0D01*
G01X1736846Y333935D02*
G03X1740783Y337872I0J3937D01*
G01Y358345D02*
Y337872D01*
G01X1744720Y362282D02*
G03X1740783Y358345I0J-3937D01*
G01X1768342Y362282D02*
X1744720D01*
G01X1713893Y407754D02*
X1717790D01*
G01X1713893Y416415D02*
Y407754D01*
G01X1739227Y416415D02*
X1741663Y407754D01*
G01X1736791D02*
X1739227Y416415D01*
G01X1729483Y407754D02*
X1733381D01*
G01X1729483Y416415D02*
Y407754D01*
G01X1747022Y412085D02*
Y407754D01*
G01X1745074Y416415D02*
X1747022Y412085D01*
G01X1752869Y416415D02*
X1756767D01*
G01X1752869Y407754D02*
Y416415D01*
G01X1756767Y407754D02*
X1752869D01*
G01Y412085D02*
X1755305D01*
G01X1737766Y410641D02*
X1740689D01*
G01X1747022Y412085D02*
X1748971Y416415D01*
G01X1756782Y562889D02*
X1760680D01*
G01X1756782Y554227D02*
Y562889D01*
G01X1760680Y554227D02*
X1756782D01*
G01X1717806D02*
X1721703D01*
G01X1717806Y562889D02*
Y554227D01*
G01X1750271Y587070D02*
Y583172D01*
G01X1751714Y586583D02*
X1750271Y587070D01*
G01X1753158Y586095D02*
X1751714Y586583D01*
G01X1755323Y585608D02*
X1753158Y586095D01*
G01X1758932Y585121D02*
X1755323Y585608D01*
G01X1750993Y593891D02*
X1751714Y594378D01*
G01X1750271Y592916D02*
X1750993Y593891D01*
G01Y591942D02*
X1750271Y592916D01*
G01X1751714Y591455D02*
X1750993Y591942D01*
G01X1753158Y590968D02*
X1751714Y591455D01*
G01X1756045Y590968D02*
X1753158D01*
G01X1757489Y591455D02*
X1756045Y590968D01*
G01X1758210Y591942D02*
X1757489Y591455D01*
G01X1758932Y592916D02*
X1758210Y591942D01*
G01Y593891D02*
X1758932Y592916D01*
G01X1757489Y594378D02*
X1758210Y593891D01*
G01X1756045Y594865D02*
X1757489Y594378D01*
G01X1754602D02*
X1756045Y594865D01*
G01X1753880Y592916D02*
X1754602Y594378D01*
G01Y591455D02*
X1753880Y592916D01*
G01X1756045Y590968D02*
X1754602Y591455D01*
G01X1750935Y558558D02*
Y554227D01*
G01X1748987Y562889D02*
X1750935Y558558D01*
G01X1733396Y554227D02*
X1737294D01*
G01X1733396Y562889D02*
Y554227D01*
G01X1743140Y562889D02*
X1745576Y554227D01*
G01X1740704D02*
X1743140Y562889D01*
G01X1750935Y558558D02*
X1752884Y562889D01*
G01X1756782Y558558D02*
X1759218D01*
G01X1741679Y557114D02*
X1744602D01*
G01X1750271Y610456D02*
Y606558D01*
G01X1751714Y609969D02*
X1750271Y610456D01*
G01X1753158Y609481D02*
X1751714Y609969D01*
G01X1755323Y608994D02*
X1753158Y609481D01*
G01X1758932Y608507D02*
X1755323Y608994D01*
G01X1758210Y600224D02*
X1758932Y600712D01*
G01Y600224D02*
X1758210D01*
G01X1758932Y600712D02*
Y600224D01*
G01X1758210Y617277D02*
X1758932Y616302D01*
G01X1757489Y617764D02*
X1758210Y617277D01*
G01X1756045Y618251D02*
X1757489Y617764D01*
G01X1753158Y618251D02*
X1756045D01*
G01X1751714Y617764D02*
X1753158Y618251D01*
G01X1750993Y617277D02*
X1751714Y617764D01*
G01X1750271Y616302D02*
X1750993Y617277D01*
G01Y615328D02*
X1750271Y616302D01*
G01X1751714Y614841D02*
X1750993Y615328D01*
G01X1753158Y614353D02*
X1751714Y614841D01*
G01X1756045Y614353D02*
X1753158D01*
G01X1757489Y614841D02*
X1756045Y614353D01*
G01X1758210Y615328D02*
X1757489Y614841D01*
G01X1758932Y616302D02*
X1758210Y615328D01*
G01X1766117Y672743D02*
G03I-5019J0D01*
G01X1772909D02*
G03I-11811J0D01*
G01X1745350Y720775D02*
Y759751D01*
G01X1760113Y708964D02*
G03X1758932I-591J0D01*
G01Y715263D02*
G03X1760113I590J0D01*
G01Y708964D02*
G03X1758932I-591J0D01*
G01Y715263D02*
G03X1760113I590J0D01*
G01X1749287Y720775D02*
G03X1745350Y716838I0J-3937D01*
G01X1741413Y692428D02*
G03X1745350Y696365I0J3937D01*
G01X1772909Y720775D02*
X1749287D01*
G01X1758342Y715263D02*
X1760704D01*
G01X1758932D02*
X1758145D01*
G01X1758932D02*
X1758145D01*
G01X1764050Y714279D02*
X1758145D01*
G01Y714082D02*
X1764050D01*
G01X1760704Y713688D02*
X1758342D01*
G01X1760704Y710539D02*
X1758342D01*
G01X1758145Y710145D02*
X1764050D01*
G01Y709948D02*
X1758145D01*
G01X1758342Y708964D02*
X1760704D01*
G01X1758145D02*
X1758932D01*
G01X1758145D02*
X1758932D01*
G01X1758342Y713688D02*
Y715263D01*
G01Y710539D02*
Y708964D01*
G01X1758145D02*
Y715263D01*
G01D02*
Y708964D01*
G01X1745350Y716838D02*
Y696365D01*
G01X1742462Y783083D02*
X1743184Y783570D01*
G01Y783083D02*
X1742462D01*
G01X1743184Y783570D02*
Y783083D01*
G01X1738132Y777237D02*
X1739575Y775288D01*
G01X1737410Y777724D02*
X1738132Y777237D01*
G01X1735966Y777724D02*
X1737410D01*
G01X1735245Y777237D02*
X1735966Y777724D01*
G01X1734523Y776262D02*
X1735245Y777237D01*
G01X1734523Y775288D02*
Y776262D01*
G01X1735245Y774313D02*
X1734523Y775288D01*
G01X1735966Y773826D02*
X1735245Y774313D01*
G01X1743184Y773826D02*
Y777724D01*
G01X1741019Y774313D02*
X1743184Y773826D01*
G01X1739575Y775288D02*
X1741019Y774313D01*
G01X1734523Y769928D02*
Y766031D01*
G01X1737410Y768954D02*
X1734523Y769928D01*
G01X1739575Y768467D02*
X1737410Y768954D01*
G01X1743184Y767980D02*
X1739575Y768467D01*
G01X1742462Y800135D02*
X1743184Y799161D01*
G01X1741741Y800622D02*
X1742462Y800135D01*
G01X1740297Y801109D02*
X1741741Y800622D01*
G01X1737410Y801109D02*
X1740297D01*
G01X1735966Y800622D02*
X1737410Y801109D01*
G01X1735245Y800135D02*
X1735966Y800622D01*
G01X1734523Y799161D02*
X1735245Y800135D01*
G01Y798186D02*
X1734523Y799161D01*
G01X1735966Y797699D02*
X1735245Y798186D01*
G01X1737410Y797212D02*
X1735966Y797699D01*
G01X1740297Y797212D02*
X1737410D01*
G01X1741741Y797699D02*
X1740297Y797212D01*
G01X1742462Y798186D02*
X1741741Y797699D01*
G01X1743184Y799161D02*
X1742462Y798186D01*
G01X1734523Y793314D02*
Y789417D01*
G01X1737410Y792340D02*
X1734523Y793314D01*
G01X1739575Y791853D02*
X1737410Y792340D01*
G01X1743184Y791365D02*
X1739575Y791853D01*
G01X1724337Y1559093D02*
Y1540156D01*
G01X1772279Y337872D02*
G03X1776216Y333935I3937J0D01*
G01X1861059D02*
X1776216D01*
G01X1772279Y337872D02*
Y358345D01*
G01D02*
G03X1768342Y362282I-3937J0D01*
G01X1763100Y412085D02*
X1760664D01*
G01X1764075Y412806D02*
X1763100Y412085D01*
G01X1764562Y413528D02*
X1764075Y412806D01*
G01X1764562Y414972D02*
Y413528D01*
G01X1764075Y415694D02*
X1764562Y414972D01*
G01X1763100Y416415D02*
X1764075Y415694D01*
G01X1760664Y416415D02*
X1763100D01*
G01X1760664Y407754D02*
Y416415D01*
G01X1768947Y408476D02*
X1767972Y409919D01*
G01X1769921Y407754D02*
X1768947Y408476D01*
G01X1770896Y407754D02*
X1769921D01*
G01X1771870Y408476D02*
X1770896Y407754D01*
G01X1772357Y409198D02*
X1771870Y408476D01*
G01X1772357Y410641D02*
Y409198D01*
G01X1771870Y411363D02*
X1772357Y410641D01*
G01X1768947Y413528D02*
X1771870Y411363D01*
G01X1768459Y414250D02*
X1768947Y413528D01*
G01X1768459Y414972D02*
Y414250D01*
G01X1768947Y415694D02*
X1768459Y414972D01*
G01X1769921Y416415D02*
X1768947Y415694D01*
G01X1770896Y416415D02*
X1769921D01*
G01X1771870Y415694D02*
X1770896Y416415D01*
G01X1772357Y414972D02*
X1771870Y415694D01*
G01X1778691Y409198D02*
X1777716Y407754D01*
G01X1779178Y411363D02*
X1778691Y409198D01*
G01X1779178Y412806D02*
Y411363D01*
G01X1778691Y414972D02*
X1779178Y412806D01*
G01X1777716Y416415D02*
X1778691Y414972D01*
G01X1763100Y412085D02*
X1764562Y407754D01*
G01X1772372Y555671D02*
X1771885Y556393D01*
G01X1772860Y554949D02*
X1772372Y555671D01*
G01X1773834Y554227D02*
X1772860Y554949D01*
G01X1774808Y554227D02*
X1773834D01*
G01X1775783Y554949D02*
X1774808Y554227D01*
G01X1776270Y555671D02*
X1775783Y554949D01*
G01X1776270Y557114D02*
Y555671D01*
G01X1775783Y557836D02*
X1776270Y557114D01*
G01X1774808Y558558D02*
X1775783Y557836D01*
G01X1772860Y560002D02*
X1774808Y558558D01*
G01X1772372Y560723D02*
X1772860Y560002D01*
G01X1772372Y561445D02*
Y560723D01*
G01X1772860Y562167D02*
X1772372Y561445D01*
G01X1773834Y562889D02*
X1772860Y562167D01*
G01X1774808Y562889D02*
X1773834D01*
G01X1775783Y562167D02*
X1774808Y562889D01*
G01X1776270Y561445D02*
X1775783Y562167D01*
G01X1782604Y555671D02*
X1781629Y554227D01*
G01X1783091Y557836D02*
X1782604Y555671D01*
G01X1783091Y559280D02*
Y557836D01*
G01X1782604Y561445D02*
X1783091Y559280D01*
G01X1781629Y562889D02*
X1782604Y561445D01*
G01X1767013Y558558D02*
X1764577D01*
G01X1767988Y559280D02*
X1767013Y558558D01*
G01X1768475Y560002D02*
X1767988Y559280D01*
G01X1768475Y561445D02*
Y560002D01*
G01X1767988Y562167D02*
X1768475Y561445D01*
G01X1767013Y562889D02*
X1767988Y562167D01*
G01X1764577Y562889D02*
X1767013D01*
G01X1764577Y554227D02*
Y562889D01*
G01X1767013Y558558D02*
X1768475Y554227D01*
G01X1761098Y668806D02*
Y624531D01*
G01X1776846Y720775D02*
Y759751D01*
G01X1762082Y715263D02*
G03X1763263I591J0D01*
G01Y708964D02*
G03X1762082I-591J0D01*
G01Y715263D02*
G03X1763263I591J0D01*
G01Y708964D02*
G03X1762082I-591J0D01*
G01X1776846Y716838D02*
G03X1772909Y720775I-3937J0D01*
G01X1776846Y696365D02*
G03X1780783Y692428I3937J0D01*
G01X1761491Y715263D02*
X1763853D01*
G01X1762082D02*
X1760113D01*
G01X1762082D02*
X1760113D01*
G01X1764050D02*
X1763263D01*
G01X1764050D02*
X1763263D01*
G01X1762393Y713996D02*
X1762352Y713987D01*
G01X1762385Y714155D02*
X1762361Y714163D01*
G01X1762352Y714205D02*
X1762393Y714197D01*
G01X1763082Y714205D02*
X1763132D01*
G01X1762918D02*
X1762968D01*
G01X1762639D02*
X1762713D01*
G01X1762525D02*
X1762574D01*
G01X1762156D02*
X1762352D01*
G01X1762361Y714163D02*
X1762205D01*
G01Y714038D02*
X1762361D01*
G01X1762352Y713987D02*
X1762205D01*
G01X1763132Y713811D02*
X1763082D01*
G01X1762968D02*
X1762894D01*
G01X1762689D02*
X1762639D01*
G01X1762574D02*
X1762525D01*
G01X1762205D02*
X1762156D01*
G01X1763853Y713688D02*
X1761491D01*
G01X1763853Y710539D02*
X1761491D01*
G01X1763263Y708964D02*
X1764050D01*
G01X1763263D02*
X1764050D01*
G01X1761491D02*
X1763853D01*
G01X1760113D02*
X1762082D01*
G01X1760113D02*
X1762082D01*
G01X1865625Y692428D02*
X1780783D01*
G01X1762393Y714197D02*
X1762426Y714172D01*
G01X1762894Y713811D02*
X1762689Y714155D01*
G01X1762713Y714205D02*
X1762918Y713870D01*
G01X1762426Y714172D02*
X1762451Y714138D01*
G01X1762402D02*
X1762385Y714155D01*
G01X1762361Y714038D02*
X1762385Y714046D01*
G01X1762451Y714138D02*
X1762459Y714113D01*
G01X1762410D02*
X1762402Y714138D01*
G01X1762426Y714021D02*
X1762393Y713996D01*
G01X1762385Y714046D02*
X1762402Y714063D01*
G01X1763082Y714138D02*
X1763033Y714079D01*
G01Y714146D02*
X1763082Y714205D01*
G01X1762451Y714054D02*
X1762426Y714021D01*
G01X1762459Y714079D02*
X1762451Y714054D01*
G01X1762402Y714063D02*
X1762410Y714088D01*
G01X1776846Y696365D02*
Y716838D01*
G01X1764050Y708964D02*
Y715263D01*
G01Y708964D02*
Y715263D01*
G01X1763853Y708964D02*
Y710539D01*
G01Y715263D02*
Y713688D01*
G01X1763132Y714205D02*
Y713811D01*
G01X1763082D02*
Y714138D01*
G01X1763033Y714079D02*
Y714146D01*
G01X1762968Y714205D02*
Y713811D01*
G01X1762918Y713870D02*
Y714205D01*
G01X1762689Y714155D02*
Y713811D01*
G01X1762639D02*
Y714205D01*
G01X1762574D02*
Y713811D01*
G01X1762525D02*
Y714205D01*
G01X1762459Y714113D02*
Y714079D01*
G01X1762410Y714088D02*
Y714113D01*
G01X1762205Y714163D02*
Y714038D01*
G01Y713987D02*
Y713811D01*
G01X1762156D02*
Y714205D01*
G01X1761491Y713688D02*
Y715263D01*
G01Y710539D02*
Y708964D01*
G01X1760704D02*
Y710539D01*
G01Y715263D02*
Y713688D01*
G01X1774680Y768467D02*
Y767492D01*
G01X1773958Y769441D02*
X1774680Y768467D01*
G01X1773237Y769928D02*
X1773958Y769441D01*
G01X1772515Y770416D02*
X1773237Y769928D01*
G01X1771793Y770416D02*
X1772515D01*
G01X1770350Y769441D02*
X1771793Y770416D01*
G01X1773958Y776749D02*
X1774680Y775775D01*
G01X1773237Y777237D02*
X1773958Y776749D01*
G01X1771793Y777724D02*
X1773237Y777237D01*
G01X1768906Y777724D02*
X1771793D01*
G01X1767462Y777237D02*
X1768906Y777724D01*
G01X1766741Y776749D02*
X1767462Y777237D01*
G01X1766019Y775775D02*
X1766741Y776749D01*
G01Y774800D02*
X1766019Y775775D01*
G01X1767462Y774313D02*
X1766741Y774800D01*
G01X1768906Y773826D02*
X1767462Y774313D01*
G01X1771793Y773826D02*
X1768906D01*
G01X1773237Y774313D02*
X1771793Y773826D01*
G01X1773958Y774800D02*
X1773237Y774313D01*
G01X1774680Y775775D02*
X1773958Y774800D01*
G01X1768906Y769441D02*
X1769628Y768467D01*
G01X1768184Y769928D02*
X1768906Y769441D01*
G01X1767462Y769928D02*
X1768184D01*
G01X1766741Y769441D02*
X1767462Y769928D01*
G01X1766019Y768467D02*
X1766741Y769441D01*
G01X1766019Y767492D02*
Y768467D01*
G01X1766741Y766518D02*
X1766019Y767492D01*
G01X1767462Y766031D02*
X1766741Y766518D01*
G01X1768184Y766031D02*
X1767462D01*
G01X1768906Y766518D02*
X1768184Y766031D01*
G01X1769628Y767492D02*
X1768906Y766518D01*
G01X1769628Y768467D02*
X1770350Y769441D01*
G01X1769628Y767492D02*
Y768467D01*
G01X1770350Y766518D02*
X1769628Y767492D01*
G01X1771071Y766031D02*
X1770350Y766518D01*
G01X1771793Y765544D02*
X1771071Y766031D01*
G01X1772515Y765544D02*
X1771793D01*
G01X1773958Y766518D02*
X1772515Y765544D01*
G01X1773958Y783083D02*
X1774680Y783570D01*
G01Y783083D02*
X1773958D01*
G01X1774680Y783570D02*
Y783083D01*
G01Y767492D02*
X1773958Y766518D01*
G01Y800135D02*
X1774680Y799161D01*
G01X1773237Y800622D02*
X1773958Y800135D01*
G01X1771793Y801109D02*
X1773237Y800622D01*
G01X1768906Y801109D02*
X1771793D01*
G01X1767462Y800622D02*
X1768906Y801109D01*
G01X1766741Y800135D02*
X1767462Y800622D01*
G01X1766019Y799161D02*
X1766741Y800135D01*
G01Y798186D02*
X1766019Y799161D01*
G01X1767462Y797699D02*
X1766741Y798186D01*
G01X1768906Y797212D02*
X1767462Y797699D01*
G01X1771793Y797212D02*
X1768906D01*
G01X1773237Y797699D02*
X1771793Y797212D01*
G01X1773958Y798186D02*
X1773237Y797699D01*
G01X1774680Y799161D02*
X1773958Y798186D01*
G01X1771071Y791853D02*
X1768906Y792340D01*
G01X1774680Y791365D02*
X1771071Y791853D01*
G01X1766019Y793314D02*
Y789417D01*
G01X1768906Y792340D02*
X1766019Y793314D01*
G01X1770113Y1540156D02*
X2277987D01*
G01X1813419Y-519029D02*
Y-323507D01*
G01X1854691Y323155D02*
X1854445Y323658D01*
G01X1852230D02*
X1851984Y323155D01*
G01X1854691Y317124D02*
Y323155D01*
G01X1851984D02*
Y317124D01*
G01X1850754D02*
Y323155D01*
G01X1848047Y323406D02*
Y317124D01*
G01Y325166D02*
Y324412D01*
G01X1846817Y317124D02*
Y325166D01*
G01X1844356Y327176D02*
X1844602Y326171D01*
G01Y321899D02*
X1844848Y320894D01*
G01X1836236Y319134D02*
X1835990Y319888D01*
G01X1850754Y323155D02*
X1850508Y323658D01*
G01X1843618Y320894D02*
X1843126Y321899D01*
G01X1837220Y319888D02*
X1837466Y319386D01*
G01X1843372Y326171D02*
X1842880Y326925D01*
G01X1844110Y322653D02*
X1844602Y321899D01*
G01X1833529Y325668D02*
X1834021Y324914D01*
G01X1836728Y318381D02*
X1836236Y319134D01*
G01X1854445Y323658D02*
X1854198Y323909D01*
G01X1851000Y324914D02*
X1851738Y324160D01*
G01X1850508Y323658D02*
X1850261Y323909D01*
G01X1843372Y328181D02*
X1844356Y327176D01*
G01X1837466Y319386D02*
X1837958Y318883D01*
G01X1842880Y326925D02*
X1842141Y327427D01*
G01X1843126Y321899D02*
X1842387Y322401D01*
G01X1854198Y323909D02*
X1853706Y324160D01*
G01X1842387Y328684D02*
X1843372Y328181D01*
G01X1850261Y323909D02*
X1849769Y324160D01*
G01X1842880Y323155D02*
X1844110Y322653D01*
G01X1854198Y325166D02*
X1854937Y324914D01*
G01X1850261Y325166D02*
X1851000Y324914D01*
G01X1842141Y327427D02*
X1840911Y327679D01*
G01X1840665Y328935D02*
X1842387Y328684D01*
G01X1852476Y324914D02*
X1853214Y325166D01*
G01X1849277Y324160D02*
X1848539Y323909D01*
G01Y324914D02*
X1849277Y325166D01*
G01X1840911Y323658D02*
X1842387Y324160D01*
G01X1843372Y317878D02*
X1842387Y317375D01*
G01Y318632D02*
X1842880Y318883D01*
G01X1852968Y324160D02*
X1852476Y323909D01*
G01X1834021Y324914D02*
X1830576Y323155D01*
G01X1837466Y328181D02*
X1838450Y328684D01*
G01X1828854Y323155D02*
X1833529Y325668D01*
G01X1844110Y318381D02*
X1843372Y317878D01*
G01X1838697Y327427D02*
X1837958Y326925D01*
G01X1843864Y323909D02*
X1842880Y323155D01*
G01X1852476Y323909D02*
X1852230Y323658D01*
G01X1851738Y324160D02*
X1852476Y324914D01*
G01X1848539Y323909D02*
X1848047Y323406D01*
G01X1842880Y318883D02*
X1843372Y319386D01*
G01X1848047Y324412D02*
X1848539Y324914D01*
G01X1842387Y324160D02*
X1842880Y324663D01*
G01X1836482Y327176D02*
X1837466Y328181D01*
G01X1844602Y319134D02*
X1844110Y318381D01*
G01X1844356Y324663D02*
X1843864Y323909D01*
G01X1837958Y326925D02*
X1837466Y326171D01*
G01X1834021Y321396D02*
X1833529Y320642D01*
G01X1843372Y319386D02*
X1843618Y319888D01*
G01X1842880Y324663D02*
X1843372Y325668D01*
G01X1844848Y319888D02*
X1844602Y319134D01*
G01Y325668D02*
X1844356Y324663D01*
G01X1836236Y326171D02*
X1836482Y327176D01*
G01X1844848Y320894D02*
Y319888D01*
G01X1844602Y326171D02*
Y325668D01*
G01X1843618Y319888D02*
Y320894D01*
G01X1843372Y325668D02*
Y326171D01*
G01X1839927Y322653D02*
Y323658D01*
G01X1826885Y328935D02*
Y317124D01*
G01X1825409Y324160D02*
Y328935D01*
G01Y317124D02*
Y322653D01*
G01X1837466Y317878D02*
X1836728Y318381D01*
G01X1833529Y320642D02*
X1828854Y323155D01*
G01X1830576D02*
X1834021Y321396D01*
G01X1837958Y318883D02*
X1838450Y318632D01*
G01Y317375D02*
X1837466Y317878D01*
G01X1839435Y317124D02*
X1838450Y317375D01*
G01Y318632D02*
X1839681Y318381D01*
G01X1842387Y322401D02*
X1840911Y322653D01*
G01X1840173Y328935D02*
X1840665D01*
G01X1825409D02*
X1826885D01*
G01X1817043D02*
X1818519D01*
G01X1840911Y327679D02*
X1839927D01*
G01X1837466Y326171D02*
X1836236D01*
G01X1853214Y325166D02*
X1854198D01*
G01X1849277D02*
X1850261D01*
G01X1846817D02*
X1848047D01*
G01X1818519Y324160D02*
X1825409D01*
G01X1849769D02*
X1849277D01*
G01X1853706D02*
X1852968D01*
G01X1839927Y323658D02*
X1840911D01*
G01X1825409Y322653D02*
X1818519D01*
G01X1840911D02*
X1839927D01*
G01X1835990Y319888D02*
X1837220D01*
G01X1839681Y318381D02*
X1841157D01*
G01X1818519Y317124D02*
X1817043D01*
G01X1826885D02*
X1825409D01*
G01X1841403D02*
X1839435D01*
G01X1848047D02*
X1846817D01*
G01X1851984D02*
X1850754D01*
G01X1855921D02*
X1854691D01*
G01X1838450Y328684D02*
X1840173Y328935D01*
G01X1839927Y327679D02*
X1838697Y327427D01*
G01X1841157Y318381D02*
X1842387Y318632D01*
G01Y317375D02*
X1841403Y317124D01*
G01X1818519Y322653D02*
Y317124D01*
G01Y328935D02*
Y324160D01*
G01X1817043Y317124D02*
Y328935D01*
G01X1861059Y333935D02*
G03X1864996Y337872I0J3937D01*
G01X1896492D02*
G03X1900429Y333935I3937J0D01*
G01X1896492Y337872D02*
Y358345D01*
G01X1866502Y324412D02*
X1866994Y323155D01*
G01X1855429Y324412D02*
X1855921Y323155D01*
G01X1865763D02*
X1865517Y323658D01*
G01X1861826Y323155D02*
X1861580Y323658D01*
G01X1866010Y324914D02*
X1866502Y324412D01*
G01X1865517Y323658D02*
X1865271Y323909D01*
G01X1862073Y324914D02*
X1862811Y324160D01*
G01X1863549Y323909D02*
X1863303Y323658D01*
G01X1862811Y324160D02*
X1863549Y324914D01*
G01X1859612Y323909D02*
X1859120Y323406D01*
G01Y324412D02*
X1859612Y324914D01*
G01X1863303Y323658D02*
X1863057Y323155D01*
G01X1866994D02*
Y317124D01*
G01X1865763D02*
Y323155D01*
G01X1864996Y358345D02*
Y337872D01*
G01X1863057Y323155D02*
Y317124D01*
G01X1861826D02*
Y323155D01*
G01X1859120Y323406D02*
Y317124D01*
G01Y325166D02*
Y324412D01*
G01X1857889Y317124D02*
Y325166D01*
G01X1855921Y323155D02*
Y317124D01*
G01X1861580Y323658D02*
X1861334Y323909D01*
G01X1854937Y324914D02*
X1855429Y324412D01*
G01X1865271Y323909D02*
X1864779Y324160D01*
G01X1861334Y323909D02*
X1860842Y324160D01*
G01X1865271Y325166D02*
X1866010Y324914D01*
G01X1861334Y325166D02*
X1862073Y324914D01*
G01X1985271Y333935D02*
X1900429D01*
G01X1863549Y324914D02*
X1864287Y325166D01*
G01X1860350Y324160D02*
X1859612Y323909D01*
G01Y324914D02*
X1860350Y325166D01*
G01X1864041Y324160D02*
X1863549Y323909D01*
G01X1864287Y325166D02*
X1865271D01*
G01X1860350D02*
X1861334D01*
G01X1857889D02*
X1859120D01*
G01X1860842Y324160D02*
X1860350D01*
G01X1864779D02*
X1864041D01*
G01X1859120Y317124D02*
X1857889D01*
G01X1863057D02*
X1861826D01*
G01X1866994D02*
X1865763D01*
G01X1868933Y362282D02*
G03X1864996Y358345I0J-3937D01*
G01X1896492D02*
G03X1892555Y362282I-3937J0D01*
G01D02*
X1868933D01*
G01X1901905Y685983D02*
X1901688Y687088D01*
G01Y682887D02*
X1901905Y683992D01*
G01X1900605Y682887D02*
X1900822Y684213D01*
G01X1901905Y683992D02*
Y685983D01*
G01X1900822Y684213D02*
Y685761D01*
G01D02*
X1900605Y687088D01*
G01X1895192Y684213D02*
X1895409Y682887D01*
G01X1894109Y683992D02*
X1894326Y682887D01*
G01X1901688Y687088D02*
X1901472Y687752D01*
G01X1894326Y682887D02*
X1894542Y682223D01*
G01X1901472Y687752D02*
X1901039Y688636D01*
G01X1894542Y682223D02*
X1894976Y681339D01*
G01X1900605Y687088D02*
X1899739Y688415D01*
G01X1895409Y682887D02*
X1896275Y681560D01*
G01X1891944Y687309D02*
X1892377Y686646D01*
G01X1901039Y688636D02*
X1900389Y689300D01*
G01Y680675D02*
X1901039Y681339D01*
G01X1899739Y681560D02*
X1900605Y682887D01*
G01X1896275Y688415D02*
X1895409Y687088D01*
G01X1892377Y683550D02*
X1891944Y682887D01*
G01X1901039Y681339D02*
X1901472Y682223D01*
G01X1894976Y688636D02*
X1894542Y687752D01*
G01X1901472Y682223D02*
X1901688Y682887D01*
G01X1894542Y687752D02*
X1894326Y687088D01*
G01D02*
X1894109Y685983D01*
G01X1895409Y687088D02*
X1895192Y685761D01*
G01D02*
Y684213D01*
G01X1894109Y685983D02*
Y683992D01*
G01X1886098Y690184D02*
Y679791D01*
G01X1884798Y685983D02*
Y690184D01*
G01Y679791D02*
Y684656D01*
G01X1878735D02*
Y679791D01*
G01Y690184D02*
Y685983D01*
G01X1877436Y679791D02*
Y690184D01*
G01X1894976Y681339D02*
X1895625Y680675D01*
G01X1899739Y688415D02*
X1899090Y688857D01*
G01X1896275Y681560D02*
X1896924Y681117D01*
G01X1900389Y689300D02*
X1899306Y689963D01*
G01X1895625Y680675D02*
X1896708Y680012D01*
G01X1891944Y682887D02*
X1887830Y685098D01*
G01X1889346D02*
X1892377Y683550D01*
G01Y686646D02*
X1889346Y685098D01*
G01X1887830D02*
X1891944Y687309D01*
G01X1899306Y680012D02*
X1900389Y680675D01*
G01X1896708Y689963D02*
X1895625Y689300D01*
G01X1899090Y681117D02*
X1899739Y681560D01*
G01X1896924Y688857D02*
X1896275Y688415D01*
G01X1895625Y689300D02*
X1894976Y688636D01*
G01X1899090Y688857D02*
X1898007Y689079D01*
G01X1896924Y681117D02*
X1898007Y680896D01*
G01X1899306Y689963D02*
X1898007Y690184D01*
G01X1896708Y680012D02*
X1898007Y679791D01*
G01X1884798Y690184D02*
X1886098D01*
G01X1877436D02*
X1878735D01*
G01Y685983D02*
X1884798D01*
G01Y684656D02*
X1878735D01*
G01Y679791D02*
X1877436D01*
G01X1886098D02*
X1884798D01*
G01X1898007Y690184D02*
X1896708Y689963D01*
G01X1898007Y679791D02*
X1899306Y680012D01*
G01X1898007Y689079D02*
X1896924Y688857D01*
G01X1898007Y680896D02*
X1899090Y681117D01*
G01X1869562Y720775D02*
Y759751D01*
G01X1901058Y720775D02*
Y759751D01*
G01X1886294Y715263D02*
G03X1887476I591J0D01*
G01Y708964D02*
G03X1886294I-591J0D01*
G01X1884326D02*
G03X1883145I-590J0D01*
G01Y715263D02*
G03X1884326I590J0D01*
G01X1886294D02*
G03X1887476I591J0D01*
G01Y708964D02*
G03X1886294I-591J0D01*
G01X1884326D02*
G03X1883145I-590J0D01*
G01Y715263D02*
G03X1884326I590J0D01*
G01X1873499Y720775D02*
G03X1869562Y716838I0J-3937D01*
G01X1901058D02*
G03X1897121Y720775I-3937J0D01*
G01X1865625Y692428D02*
G03X1869562Y696365I0J3937D01*
G01X1901058D02*
G03X1904995Y692428I3937J0D01*
G01X1901058Y696365D02*
Y716838D01*
G01X1886663Y714138D02*
X1886672Y714113D01*
G01X1886622D02*
X1886614Y714138D01*
G01X1887106Y713811D02*
X1886901Y714155D01*
G01X1886926Y714205D02*
X1887131Y713870D01*
G01X1886639Y714172D02*
X1886663Y714138D01*
G01X1886614D02*
X1886598Y714155D01*
G01X1886606Y714197D02*
X1886639Y714172D01*
G01X1888263Y708964D02*
Y715263D01*
G01Y708964D02*
Y715263D01*
G01X1888066Y708964D02*
Y710539D01*
G01Y715263D02*
Y713688D01*
G01X1887344Y714205D02*
Y713811D01*
G01X1887295D02*
Y714138D01*
G01X1887246Y714079D02*
Y714146D01*
G01X1887180Y714205D02*
Y713811D01*
G01X1887131Y713870D02*
Y714205D01*
G01X1886901Y714155D02*
Y713811D01*
G01X1886852D02*
Y714205D01*
G01X1886786D02*
Y713811D01*
G01X1886737D02*
Y714205D01*
G01X1886672Y714113D02*
Y714079D01*
G01X1886622Y714088D02*
Y714113D01*
G01X1886417Y714163D02*
Y714038D01*
G01Y713987D02*
Y713811D01*
G01X1886368D02*
Y714205D01*
G01X1885704Y713688D02*
Y715263D01*
G01Y710539D02*
Y708964D01*
G01X1884916D02*
Y710539D01*
G01Y715263D02*
Y713688D01*
G01X1882554D02*
Y715263D01*
G01Y710539D02*
Y708964D01*
G01X1882357D02*
Y715263D01*
G01D02*
Y708964D01*
G01X1886598Y714155D02*
X1886573Y714163D01*
G01X1886565Y714205D02*
X1886606Y714197D01*
G01X1897121Y720775D02*
X1873499D01*
G01X1885704Y715263D02*
X1888066D01*
G01X1882554D02*
X1884916D01*
G01X1883145D02*
X1882357D01*
G01X1883145D02*
X1882357D01*
G01X1886294D02*
X1884326D01*
G01X1886294D02*
X1884326D01*
G01X1888263D02*
X1887476D01*
G01X1888263D02*
X1887476D01*
G01X1887295Y714138D02*
X1887246Y714079D01*
G01Y714146D02*
X1887295Y714205D01*
G01X1886663Y714054D02*
X1886639Y714021D01*
G01X1886672Y714079D02*
X1886663Y714054D01*
G01X1886614Y714063D02*
X1886622Y714088D01*
G01X1869562Y716838D02*
Y696365D01*
G01X1888263Y714279D02*
X1882357D01*
G01X1887295Y714205D02*
X1887344D01*
G01X1887131D02*
X1887180D01*
G01X1886852D02*
X1886926D01*
G01X1886737D02*
X1886786D01*
G01X1886368D02*
X1886565D01*
G01X1886573Y714163D02*
X1886417D01*
G01X1882357Y714082D02*
X1888263D01*
G01X1886417Y714038D02*
X1886573D01*
G01X1886565Y713987D02*
X1886417D01*
G01X1887344Y713811D02*
X1887295D01*
G01X1887180D02*
X1887106D01*
G01X1886901D02*
X1886852D01*
G01X1886786D02*
X1886737D01*
G01X1886417D02*
X1886368D01*
G01X1884916Y713688D02*
X1882554D01*
G01X1888066D02*
X1885704D01*
G01X1884916Y710539D02*
X1882554D01*
G01X1888066D02*
X1885704D01*
G01X1882357Y710145D02*
X1888263D01*
G01Y709948D02*
X1882357D01*
G01X1887476Y708964D02*
X1888263D01*
G01X1887476D02*
X1888263D01*
G01X1885704D02*
X1888066D01*
G01X1884326D02*
X1886294D01*
G01X1884326D02*
X1886294D01*
G01X1882554D02*
X1884916D01*
G01X1882357D02*
X1883145D01*
G01X1882357D02*
X1883145D01*
G01X1886606Y713996D02*
X1886565Y713987D01*
G01X1886639Y714021D02*
X1886606Y713996D01*
G01X1886598Y714046D02*
X1886614Y714063D01*
G01X1886573Y714038D02*
X1886598Y714046D01*
G01X1866675Y776749D02*
X1867397Y775775D01*
G01X1865953Y777237D02*
X1866675Y776749D01*
G01X1864510Y777724D02*
X1865953Y777237D01*
G01X1861623Y777724D02*
X1864510D01*
G01X1860179Y777237D02*
X1861623Y777724D01*
G01X1859457Y776749D02*
X1860179Y777237D01*
G01X1858735Y775775D02*
X1859457Y776749D01*
G01Y774800D02*
X1858735Y775775D01*
G01X1860179Y774313D02*
X1859457Y774800D01*
G01X1861623Y773826D02*
X1860179Y774313D01*
G01X1864510Y773826D02*
X1861623D01*
G01X1865953Y774313D02*
X1864510Y773826D01*
G01X1866675Y774800D02*
X1865953Y774313D01*
G01X1867397Y775775D02*
X1866675Y774800D01*
G01X1865231Y781621D02*
Y786006D01*
G01X1858735Y785032D02*
X1865231Y781621D01*
G01X1867397Y785032D02*
X1858735D01*
G01X1898893Y781621D02*
Y785519D01*
G01X1896728Y782109D02*
X1898893Y781621D01*
G01X1895284Y783083D02*
X1896728Y782109D01*
G01X1894562Y784057D02*
X1895284Y783083D01*
G01X1893840Y785032D02*
X1894562Y784057D01*
G01X1893119Y785519D02*
X1893840Y785032D01*
G01X1891675Y785519D02*
X1893119D01*
G01X1890953Y785032D02*
X1891675Y785519D01*
G01X1890231Y784057D02*
X1890953Y785032D01*
G01X1890231Y783083D02*
Y784057D01*
G01X1890953Y782109D02*
X1890231Y783083D01*
G01X1891675Y781621D02*
X1890953Y782109D01*
G01X1890231Y775775D02*
X1898893D01*
G01X1890231Y767980D02*
X1898893D01*
G01X1858735D02*
X1867397D01*
G01X1866675Y805494D02*
X1865953Y805007D01*
G01X1867397Y806469D02*
X1866675Y805494D01*
G01X1867397Y807443D02*
Y806469D01*
G01X1866675Y808418D02*
X1867397Y807443D01*
G01X1865953Y808905D02*
X1866675Y808418D01*
G01X1864510Y809392D02*
X1865953Y808905D01*
G01X1863066D02*
X1864510Y809392D01*
G01X1862344Y808418D02*
X1863066Y808905D01*
G01X1861623Y807443D02*
X1862344Y808418D01*
G01X1861623Y806469D02*
Y807443D01*
G01X1862344Y805494D02*
X1861623Y806469D01*
G01X1858735Y805982D02*
X1862344Y805494D01*
G01X1858735Y808905D02*
Y805982D01*
G01X1866675Y790878D02*
X1867397Y791365D01*
G01Y790878D02*
X1866675D01*
G01X1867397Y791365D02*
Y790878D01*
G01X1898171Y805494D02*
X1897449Y805007D01*
G01X1898893Y806469D02*
X1898171Y805494D01*
G01X1898893Y807443D02*
Y806469D01*
G01X1898171Y808418D02*
X1898893Y807443D01*
G01X1897449Y808905D02*
X1898171Y808418D01*
G01X1896006Y809392D02*
X1897449Y808905D01*
G01X1894562D02*
X1896006Y809392D01*
G01X1893840Y808418D02*
X1894562Y808905D01*
G01X1893119Y807443D02*
X1893840Y808418D01*
G01X1893119Y806469D02*
Y807443D01*
G01X1893840Y805494D02*
X1893119Y806469D01*
G01X1890231Y805982D02*
X1893840Y805494D01*
G01X1890231Y808905D02*
Y805982D01*
G01X1898171Y790878D02*
X1898893Y791365D01*
G01Y790878D02*
X1898171D01*
G01X1898893Y791365D02*
Y790878D01*
G01X1867397Y797212D02*
Y801109D01*
G01X1865231Y797699D02*
X1867397Y797212D01*
G01X1863788Y798673D02*
X1865231Y797699D01*
G01X1863066Y799648D02*
X1863788Y798673D01*
G01X1862344Y800622D02*
X1863066Y799648D01*
G01X1861623Y801109D02*
X1862344Y800622D01*
G01X1860179Y801109D02*
X1861623D01*
G01X1859457Y800622D02*
X1860179Y801109D01*
G01X1858735Y799648D02*
X1859457Y800622D01*
G01X1858735Y798673D02*
Y799648D01*
G01X1859457Y797699D02*
X1858735Y798673D01*
G01X1860179Y797212D02*
X1859457Y797699D01*
G01X1893840Y800622D02*
X1895284Y798673D01*
G01X1893119Y801109D02*
X1893840Y800622D01*
G01X1891675Y801109D02*
X1893119D01*
G01X1890953Y800622D02*
X1891675Y801109D01*
G01X1890231Y799648D02*
X1890953Y800622D01*
G01X1890231Y798673D02*
Y799648D01*
G01X1890953Y797699D02*
X1890231Y798673D01*
G01X1891675Y797212D02*
X1890953Y797699D01*
G01X1898893Y797212D02*
Y801109D01*
G01X1896728Y797699D02*
X1898893Y797212D01*
G01X1895284Y798673D02*
X1896728Y797699D01*
G01X1943060Y-618663D02*
Y-637600D01*
G01X1948263Y314250D02*
G03I-5019J0D01*
G01X1955055D02*
G03I-11811J0D01*
G01X1943479Y585605D02*
Y589990D01*
G01X1936983Y589016D02*
X1943479Y585605D01*
G01X1945645Y589016D02*
X1936983D01*
G01X1945645Y577810D02*
Y581708D01*
G01X1943479Y578297D02*
X1945645Y577810D01*
G01X1942036Y579272D02*
X1943479Y578297D01*
G01X1941314Y580246D02*
X1942036Y579272D01*
G01X1940592Y581221D02*
X1941314Y580246D01*
G01X1939871Y581708D02*
X1940592Y581221D01*
G01X1938427Y581708D02*
X1939871D01*
G01X1937705Y581221D02*
X1938427Y581708D01*
G01X1936983Y580246D02*
X1937705Y581221D01*
G01X1936983Y579272D02*
Y580246D01*
G01X1937705Y578297D02*
X1936983Y579272D01*
G01X1938427Y577810D02*
X1937705Y578297D01*
G01X1944923Y594862D02*
X1945645Y595350D01*
G01Y594862D02*
X1944923D01*
G01X1945645Y595350D02*
Y594862D01*
G01X1936983Y571964D02*
X1945645D01*
G01X1947810Y668806D02*
Y619168D01*
G01X1944923Y609479D02*
X1944201Y608991D01*
G01X1945645Y610453D02*
X1944923Y609479D01*
G01X1945645Y611427D02*
Y610453D01*
G01X1944923Y612402D02*
X1945645Y611427D01*
G01X1944201Y612889D02*
X1944923Y612402D01*
G01X1943479Y613376D02*
X1944201Y612889D01*
G01X1942758Y613376D02*
X1943479D01*
G01X1941314Y612402D02*
X1942758Y613376D01*
G01X1940592Y611427D02*
X1941314Y612402D01*
G01X1939871D02*
X1940592Y611427D01*
G01X1939149Y612889D02*
X1939871Y612402D01*
G01X1938427Y612889D02*
X1939149D01*
G01X1937705Y612402D02*
X1938427Y612889D01*
G01X1936983Y611427D02*
X1937705Y612402D01*
G01X1936983Y610453D02*
Y611427D01*
G01X1937705Y609479D02*
X1936983Y610453D01*
G01X1940592D02*
Y611427D01*
G01X1936983Y603145D02*
X1945645D01*
G01X1952830Y672743D02*
G03I-5020J0D01*
G01X1959621D02*
G03I-11811J0D01*
G01X1933302Y686204D02*
X1933735Y685098D01*
G01D02*
Y679791D01*
G01X1932653D02*
Y685098D01*
G01X1930271D02*
Y679791D01*
G01X1929188D02*
Y685098D01*
G01X1926806Y686867D02*
Y686204D01*
G01Y685319D02*
Y679791D01*
G01X1925724D02*
Y686867D01*
G01X1914031Y688636D02*
X1914247Y687752D01*
G01X1923558Y686204D02*
X1923991Y685098D01*
G01X1932653D02*
X1932436Y685540D01*
G01X1929188Y685098D02*
X1928972Y685540D01*
G01X1922909Y685098D02*
X1922692Y685540D01*
G01X1919444Y685098D02*
X1919227Y685540D01*
G01X1932869Y686646D02*
X1933302Y686204D01*
G01X1932436Y685540D02*
X1932220Y685761D01*
G01X1930704D02*
X1930487Y685540D01*
G01X1930054Y685983D02*
X1930704Y686646D01*
G01X1930487Y685540D02*
X1930271Y685098D01*
G01X1920743Y685540D02*
X1920527Y685098D01*
G01X1912515Y686425D02*
X1912948Y687309D01*
G01X1914247D02*
X1914031Y686425D01*
G01X1906668Y687752D02*
X1906885Y688636D01*
G01X1923991Y685098D02*
Y679791D01*
G01X1922909D02*
Y685098D01*
G01X1920527D02*
Y679791D01*
G01X1919444D02*
Y685098D01*
G01X1917062Y686867D02*
Y686204D01*
G01Y685319D02*
Y679791D01*
G01X1915979D02*
Y686867D01*
G01X1914247Y680896D02*
Y679791D01*
G01Y687752D02*
Y687309D01*
G01X1912948D02*
Y687752D01*
G01X1906452Y679791D02*
Y680896D01*
G01X1904720D02*
Y679791D01*
G01X1903637D02*
Y680896D01*
G01X1912948Y687752D02*
X1912515Y688415D01*
G01X1929405Y686646D02*
X1930054Y685983D01*
G01X1928972Y685540D02*
X1928755Y685761D01*
G01X1923125Y686646D02*
X1923558Y686204D01*
G01X1922692Y685540D02*
X1922476Y685761D01*
G01X1919661Y686646D02*
X1920310Y685983D01*
G01X1919227Y685540D02*
X1919011Y685761D01*
G01X1913165Y689521D02*
X1914031Y688636D01*
G01X1913598Y685761D02*
X1908184Y680896D01*
G01X1906452D02*
X1912515Y686425D01*
G01X1927239Y685761D02*
X1926806Y685319D01*
G01Y686204D02*
X1927239Y686646D01*
G01X1920960Y685761D02*
X1920743Y685540D01*
G01X1920310Y685983D02*
X1920960Y686646D01*
G01X1917495Y685761D02*
X1917062Y685319D01*
G01Y686204D02*
X1917495Y686646D01*
G01X1906885Y688636D02*
X1907751Y689521D01*
G01X1914031Y686425D02*
X1913598Y685761D01*
G01X1908184Y688415D02*
X1907751Y687752D01*
G01X1912515Y688415D02*
X1911865Y688857D01*
G01X1932220Y685761D02*
X1931787Y685983D01*
G01X1928755Y685761D02*
X1928322Y685983D01*
G01X1922476Y685761D02*
X1922042Y685983D01*
G01X1912298Y689963D02*
X1913165Y689521D01*
G01X1919011Y685761D02*
X1918578Y685983D01*
G01X1932220Y686867D02*
X1932869Y686646D01*
G01X1928755Y686867D02*
X1929405Y686646D01*
G01X1922476Y686867D02*
X1923125Y686646D01*
G01X1919011Y686867D02*
X1919661Y686646D01*
G01X1930704D02*
X1931353Y686867D01*
G01X1927889Y685983D02*
X1927239Y685761D01*
G01Y686646D02*
X1927889Y686867D01*
G01X1920960Y686646D02*
X1921609Y686867D01*
G01X1918145Y685983D02*
X1917495Y685761D01*
G01Y686646D02*
X1918145Y686867D01*
G01X1931137Y685983D02*
X1930704Y685761D01*
G01X1921393Y685983D02*
X1920960Y685761D01*
G01X1907751Y689521D02*
X1908617Y689963D01*
G01X1908834Y688857D02*
X1908184Y688415D01*
G01X1911865Y688857D02*
X1910783Y689079D01*
G01X1910999Y690184D02*
X1912298Y689963D01*
G01X1910133Y690184D02*
X1910999D01*
G01X1910783Y689079D02*
X1909916D01*
G01X1907751Y687752D02*
X1906668D01*
G01X1931353Y686867D02*
X1932220D01*
G01X1927889D02*
X1928755D01*
G01X1925724D02*
X1926806D01*
G01X1921609D02*
X1922476D01*
G01X1918145D02*
X1919011D01*
G01X1915979D02*
X1917062D01*
G01X1918578Y685983D02*
X1918145D01*
G01X1922042D02*
X1921393D01*
G01X1928322D02*
X1927889D01*
G01X1931787D02*
X1931137D01*
G01X1908184Y680896D02*
X1914247D01*
G01X1903637D02*
X1904720D01*
G01Y679791D02*
X1903637D01*
G01X1914247D02*
X1906452D01*
G01X1917062D02*
X1915979D01*
G01X1920527D02*
X1919444D01*
G01X1923991D02*
X1922909D01*
G01X1926806D02*
X1925724D01*
G01X1930271D02*
X1929188D01*
G01X1933735D02*
X1932653D01*
G01X1908617Y689963D02*
X1910133Y690184D01*
G01X1909916Y689079D02*
X1908834Y688857D01*
G01X1989838Y692428D02*
X1904995D01*
G01X1944006Y1559093D02*
Y1540156D01*
G01X1958262Y-618663D02*
X2608696D01*
G01X1985271Y333935D02*
G03X1989208Y337872I0J3937D01*
G01Y358345D02*
Y337872D01*
G01X1993145Y362282D02*
G03X1989208Y358345I0J-3937D01*
G01X2016767Y362282D02*
X1993145D01*
G01X1993775Y720775D02*
Y759751D01*
G01X1997712Y720775D02*
G03X1993775Y716838I0J-3937D01*
G01X1989838Y692428D02*
G03X1993775Y696365I0J3937D01*
G01Y716838D02*
Y696365D01*
G01X2021334Y720775D02*
X1997712D01*
G01X1990888Y774313D02*
X1990166Y773826D01*
G01X1991609Y775288D02*
X1990888Y774313D01*
G01X1991609Y776262D02*
Y775288D01*
G01X1990888Y777237D02*
X1991609Y776262D01*
G01X1990166Y777724D02*
X1990888Y777237D01*
G01X1989444Y778211D02*
X1990166Y777724D01*
G01X1988722Y778211D02*
X1989444D01*
G01X1990888Y782109D02*
X1990166Y781621D01*
G01X1991609Y783083D02*
X1990888Y782109D01*
G01X1991609Y784057D02*
Y783083D01*
G01X1990888Y785032D02*
X1991609Y784057D01*
G01X1990166Y785519D02*
X1990888Y785032D01*
G01X1988722Y786006D02*
X1990166Y785519D01*
G01X1987279D02*
X1988722Y786006D01*
G01X1986557Y785032D02*
X1987279Y785519D01*
G01X1985835Y784057D02*
X1986557Y785032D01*
G01X1985835Y783083D02*
Y784057D01*
G01X1986557Y782109D02*
X1985835Y783083D01*
G01X1982948Y782596D02*
X1986557Y782109D01*
G01X1982948Y785519D02*
Y782596D01*
G01X1987279Y777237D02*
X1988722Y778211D01*
G01X1986557Y776262D02*
X1987279Y777237D01*
G01X1985835D02*
X1986557Y776262D01*
G01X1985113Y777724D02*
X1985835Y777237D01*
G01X1984392Y777724D02*
X1985113D01*
G01X1983670Y777237D02*
X1984392Y777724D01*
G01X1982948Y776262D02*
X1983670Y777237D01*
G01X1982948Y775288D02*
Y776262D01*
G01X1983670Y774313D02*
X1982948Y775288D01*
G01X1986557D02*
Y776262D01*
G01X1982948Y767980D02*
X1991609D01*
G01X1990888Y807930D02*
X1991609Y806956D01*
G01X1990166Y808418D02*
X1990888Y807930D01*
G01X1988722Y808905D02*
X1990166Y808418D01*
G01X1985835Y808905D02*
X1988722D01*
G01X1984392Y808418D02*
X1985835Y808905D01*
G01X1983670Y807930D02*
X1984392Y808418D01*
G01X1982948Y806956D02*
X1983670Y807930D01*
G01Y805982D02*
X1982948Y806956D01*
G01X1984392Y805494D02*
X1983670Y805982D01*
G01X1985835Y805007D02*
X1984392Y805494D01*
G01X1988722Y805007D02*
X1985835D01*
G01X1990166Y805494D02*
X1988722Y805007D01*
G01X1990888Y805982D02*
X1990166Y805494D01*
G01X1991609Y806956D02*
X1990888Y805982D01*
G01X1985835Y800622D02*
X1986557Y799648D01*
G01X1985113Y801109D02*
X1985835Y800622D01*
G01X1984392Y801109D02*
X1985113D01*
G01X1983670Y800622D02*
X1984392Y801109D01*
G01X1982948Y799648D02*
X1983670Y800622D01*
G01X1982948Y798673D02*
Y799648D01*
G01X1983670Y797699D02*
X1982948Y798673D01*
G01X1984392Y797212D02*
X1983670Y797699D01*
G01X1985113Y797212D02*
X1984392D01*
G01X1985835Y797699D02*
X1985113Y797212D01*
G01X1986557Y798673D02*
X1985835Y797699D01*
G01X1987279Y800622D02*
X1988722Y801597D01*
G01X1986557Y799648D02*
X1987279Y800622D01*
G01X1986557Y798673D02*
Y799648D01*
G01X1987279Y797699D02*
X1986557Y798673D01*
G01X1988000Y797212D02*
X1987279Y797699D01*
G01X1988722Y796725D02*
X1988000Y797212D01*
G01X1989444Y796725D02*
X1988722D01*
G01X1990166Y797212D02*
X1989444Y796725D01*
G01X1990888Y797699D02*
X1990166Y797212D01*
G01X1991609Y798673D02*
X1990888Y797699D01*
G01X1991609Y799648D02*
Y798673D01*
G01X1990888Y800622D02*
X1991609Y799648D01*
G01X1990166Y801109D02*
X1990888Y800622D01*
G01X1989444Y801597D02*
X1990166Y801109D01*
G01X1988722Y801597D02*
X1989444D01*
G01X1990888Y790878D02*
X1991609Y791365D01*
G01Y790878D02*
X1990888D01*
G01X1991609Y791365D02*
Y790878D01*
G01X2020704Y337872D02*
G03X2024641Y333935I3937J0D01*
G01X2020704Y337872D02*
Y358345D01*
G01X2109484Y333935D02*
X2024641D01*
G01X2020704Y358345D02*
G03X2016767Y362282I-3937J0D01*
G01X2025271Y720775D02*
Y759751D01*
G01Y696365D02*
G03X2029208Y692428I3937J0D01*
G01X2010507Y715263D02*
G03X2011688I590J0D01*
G01Y708964D02*
G03X2010507I-591J0D01*
G01X2008539D02*
G03X2007357I-591J0D01*
G01Y715263D02*
G03X2008539I591J0D01*
G01X2010507D02*
G03X2011688I590J0D01*
G01Y708964D02*
G03X2010507I-591J0D01*
G01X2008539D02*
G03X2007357I-591J0D01*
G01Y715263D02*
G03X2008539I591J0D01*
G01X2025271Y716838D02*
G03X2021334Y720775I-3937J0D01*
G01X2025271Y696365D02*
Y716838D01*
G01X2010876Y714138D02*
X2010884Y714113D01*
G01X2010835D02*
X2010827Y714138D01*
G01X2011319Y713811D02*
X2011114Y714155D01*
G01X2011138Y714205D02*
X2011344Y713870D01*
G01X2012476Y708964D02*
Y715263D01*
G01Y708964D02*
Y715263D01*
G01X2012279Y708964D02*
Y710539D01*
G01Y715263D02*
Y713688D01*
G01X2011557Y714205D02*
Y713811D01*
G01X2011508D02*
Y714138D01*
G01X2011458Y714079D02*
Y714146D01*
G01X2011393Y714205D02*
Y713811D01*
G01X2011344Y713870D02*
Y714205D01*
G01X2011114Y714155D02*
Y713811D01*
G01X2011065D02*
Y714205D01*
G01X2010999D02*
Y713811D01*
G01X2010950D02*
Y714205D01*
G01X2010884Y714113D02*
Y714079D01*
G01X2010835Y714088D02*
Y714113D01*
G01X2010630Y714163D02*
Y714038D01*
G01Y713987D02*
Y713811D01*
G01X2010581D02*
Y714205D01*
G01X2009916Y713688D02*
Y715263D01*
G01Y710539D02*
Y708964D01*
G01X2009129D02*
Y710539D01*
G01Y715263D02*
Y713688D01*
G01X2006767D02*
Y715263D01*
G01Y710539D02*
Y708964D01*
G01X2006570D02*
Y715263D01*
G01D02*
Y708964D01*
G01X2010851Y714172D02*
X2010876Y714138D01*
G01X2010827D02*
X2010810Y714155D01*
G01X2010884Y714079D02*
X2010876Y714054D01*
G01X2010827Y714063D02*
X2010835Y714088D01*
G01X2010819Y714197D02*
X2010851Y714172D01*
G01X2011508Y714138D02*
X2011458Y714079D01*
G01Y714146D02*
X2011508Y714205D01*
G01X2010876Y714054D02*
X2010851Y714021D01*
G01X2010810Y714046D02*
X2010827Y714063D01*
G01X2010810Y714155D02*
X2010786Y714163D01*
G01X2010851Y714021D02*
X2010819Y713996D01*
G01X2010778Y714205D02*
X2010819Y714197D01*
G01X2009916Y715263D02*
X2012279D01*
G01X2006767D02*
X2009129D01*
G01X2007357D02*
X2006570D01*
G01X2007357D02*
X2006570D01*
G01X2010507D02*
X2008539D01*
G01X2010507D02*
X2008539D01*
G01X2012476D02*
X2011688D01*
G01X2012476D02*
X2011688D01*
G01X2010786Y714038D02*
X2010810Y714046D01*
G01X2012476Y714279D02*
X2006570D01*
G01X2011508Y714205D02*
X2011557D01*
G01X2011344D02*
X2011393D01*
G01X2011065D02*
X2011138D01*
G01X2010950D02*
X2010999D01*
G01X2010581D02*
X2010778D01*
G01X2010786Y714163D02*
X2010630D01*
G01X2006570Y714082D02*
X2012476D01*
G01X2010630Y714038D02*
X2010786D01*
G01X2010778Y713987D02*
X2010630D01*
G01X2011557Y713811D02*
X2011508D01*
G01X2011393D02*
X2011319D01*
G01X2011114D02*
X2011065D01*
G01X2010999D02*
X2010950D01*
G01X2010630D02*
X2010581D01*
G01X2009129Y713688D02*
X2006767D01*
G01X2012279D02*
X2009916D01*
G01X2009129Y710539D02*
X2006767D01*
G01X2012279D02*
X2009916D01*
G01X2006570Y710145D02*
X2012476D01*
G01Y709948D02*
X2006570D01*
G01X2009916Y708964D02*
X2012279D01*
G01X2011688D02*
X2012476D01*
G01X2011688D02*
X2012476D01*
G01X2008539D02*
X2010507D01*
G01X2008539D02*
X2010507D01*
G01X2006767D02*
X2009129D01*
G01X2006570D02*
X2007357D01*
G01X2006570D02*
X2007357D01*
G01X2114050Y692428D02*
X2029208D01*
G01X2010819Y713996D02*
X2010778Y713987D01*
G01X2020940Y773826D02*
Y778211D01*
G01X2014444Y777237D02*
X2020940Y773826D01*
G01X2023105Y777237D02*
X2014444D01*
G01X2022384Y782109D02*
X2021662Y781621D01*
G01X2023105Y783083D02*
X2022384Y782109D01*
G01X2023105Y784057D02*
Y783083D01*
G01X2022384Y785032D02*
X2023105Y784057D01*
G01X2021662Y785519D02*
X2022384Y785032D01*
G01X2020940Y786006D02*
X2021662Y785519D01*
G01X2020218Y786006D02*
X2020940D01*
G01X2019497Y785519D02*
X2020218Y786006D01*
G01X2018775Y785032D02*
X2019497Y785519D01*
G01X2018053Y784057D02*
X2018775Y785032D01*
G01X2017331D02*
X2018053Y784057D01*
G01X2016609Y785519D02*
X2017331Y785032D01*
G01X2015888Y785519D02*
X2016609D01*
G01X2015166Y785032D02*
X2015888Y785519D01*
G01X2014444Y784057D02*
X2015166Y785032D01*
G01X2014444Y783083D02*
Y784057D01*
G01X2015166Y782109D02*
X2014444Y783083D01*
G01X2018053D02*
Y784057D01*
G01X2014444Y767980D02*
X2023105D01*
G01X2022384Y807930D02*
X2023105Y806956D01*
G01X2021662Y808418D02*
X2022384Y807930D01*
G01X2020218Y808905D02*
X2021662Y808418D01*
G01X2017331Y808905D02*
X2020218D01*
G01X2015888Y808418D02*
X2017331Y808905D01*
G01X2015166Y807930D02*
X2015888Y808418D01*
G01X2014444Y806956D02*
X2015166Y807930D01*
G01Y805982D02*
X2014444Y806956D01*
G01X2015888Y805494D02*
X2015166Y805982D01*
G01X2017331Y805007D02*
X2015888Y805494D01*
G01X2020218Y805007D02*
X2017331D01*
G01X2021662Y805494D02*
X2020218Y805007D01*
G01X2022384Y805982D02*
X2021662Y805494D01*
G01X2023105Y806956D02*
X2022384Y805982D01*
G01X2017331Y800622D02*
X2018053Y799648D01*
G01X2016609Y801109D02*
X2017331Y800622D01*
G01X2015888Y801109D02*
X2016609D01*
G01X2015166Y800622D02*
X2015888Y801109D01*
G01X2014444Y799648D02*
X2015166Y800622D01*
G01X2014444Y798673D02*
Y799648D01*
G01X2015166Y797699D02*
X2014444Y798673D01*
G01X2015888Y797212D02*
X2015166Y797699D01*
G01X2016609Y797212D02*
X2015888D01*
G01X2017331Y797699D02*
X2016609Y797212D01*
G01X2018053Y798673D02*
X2017331Y797699D01*
G01X2018775Y800622D02*
X2020218Y801597D01*
G01X2018053Y799648D02*
X2018775Y800622D01*
G01X2018053Y798673D02*
Y799648D01*
G01X2018775Y797699D02*
X2018053Y798673D01*
G01X2019497Y797212D02*
X2018775Y797699D01*
G01X2020218Y796725D02*
X2019497Y797212D01*
G01X2020940Y796725D02*
X2020218D01*
G01X2021662Y797212D02*
X2020940Y796725D01*
G01X2022384Y797699D02*
X2021662Y797212D01*
G01X2023105Y798673D02*
X2022384Y797699D01*
G01X2023105Y799648D02*
Y798673D01*
G01X2022384Y800622D02*
X2023105Y799648D01*
G01X2021662Y801109D02*
X2022384Y800622D01*
G01X2020940Y801597D02*
X2021662Y801109D01*
G01X2020218Y801597D02*
X2020940D01*
G01X2022384Y790878D02*
X2023105Y791365D01*
G01Y790878D02*
X2022384D01*
G01X2023105Y791365D02*
Y790878D01*
G01X2138950Y309970D02*
X2177735Y266023D01*
G01X2140882Y314250D02*
G03I-5709J0D01*
G01X2109484Y333935D02*
G03X2113421Y337872I0J3937D01*
G01Y358345D02*
Y337872D01*
G01X2117358Y362282D02*
G03X2113421Y358345I0J-3937D01*
G01X2144917D02*
G03X2140980Y362282I-3937J0D01*
G01D02*
X2117358D01*
G01X2128913Y546066D02*
X2137574D01*
G01X2139739Y668806D02*
Y593271D01*
G01X2137574Y577734D02*
Y576760D01*
G01X2136852Y578709D02*
X2137574Y577734D01*
G01X2136130Y579196D02*
X2136852Y578709D01*
G01X2135409Y579683D02*
X2136130Y579196D01*
G01X2134687Y579683D02*
X2135409D01*
G01X2133965Y579196D02*
X2134687Y579683D01*
G01X2133243Y578709D02*
X2133965Y579196D01*
G01X2132521Y577734D02*
X2133243Y578709D01*
G01X2132521Y576760D02*
Y577734D01*
G01X2133243Y575785D02*
X2132521Y576760D01*
G01X2133965Y575298D02*
X2133243Y575785D01*
G01X2134687Y574811D02*
X2133965Y575298D01*
G01X2135409Y574811D02*
X2134687D01*
G01X2128913Y555810D02*
Y551912D01*
G01X2130356Y555323D02*
X2128913Y555810D01*
G01X2131800Y554836D02*
X2130356Y555323D01*
G01X2133965Y554348D02*
X2131800Y554836D01*
G01X2137574Y553861D02*
X2133965Y554348D01*
G01X2131800Y563605D02*
X2132521Y563118D01*
G01X2130356Y563605D02*
X2131800D01*
G01X2129634Y563118D02*
X2130356Y563605D01*
G01X2128913Y562144D02*
X2129634Y563118D01*
G01X2128913Y561169D02*
Y562144D01*
G01X2129634Y560195D02*
X2128913Y561169D01*
G01X2130356Y559708D02*
X2129634Y560195D01*
G01X2137574Y559708D02*
Y563605D01*
G01X2135409Y560195D02*
X2137574Y559708D01*
G01X2133965Y561169D02*
X2135409Y560195D01*
G01X2132521Y563118D02*
X2133965Y561169D01*
G01X2137574Y585530D02*
Y584555D01*
G01X2136852Y586504D02*
X2137574Y585530D01*
G01X2136130Y586991D02*
X2136852Y586504D01*
G01X2135409Y587478D02*
X2136130Y586991D01*
G01X2134687Y587478D02*
X2135409D01*
G01X2133243Y586504D02*
X2134687Y587478D01*
G01X2136852Y568965D02*
X2137574Y569452D01*
G01Y568965D02*
X2136852D01*
G01X2137574Y569452D02*
Y568965D01*
G01X2131800Y586504D02*
X2132521Y585530D01*
G01X2131078Y586991D02*
X2131800Y586504D01*
G01X2130356Y586991D02*
X2131078D01*
G01X2129634Y586504D02*
X2130356Y586991D01*
G01X2128913Y585530D02*
X2129634Y586504D01*
G01X2128913Y584555D02*
Y585530D01*
G01X2129634Y583581D02*
X2128913Y584555D01*
G01X2130356Y583094D02*
X2129634Y583581D01*
G01X2131078Y583094D02*
X2130356D01*
G01X2131800Y583581D02*
X2131078Y583094D01*
G01X2132521Y584555D02*
X2131800Y583581D01*
G01X2132521Y585530D02*
X2133243Y586504D01*
G01X2132521Y584555D02*
Y585530D01*
G01X2133243Y583581D02*
X2132521Y584555D01*
G01X2133965Y583094D02*
X2133243Y583581D01*
G01X2134687Y582606D02*
X2133965Y583094D01*
G01X2135409Y582606D02*
X2134687D01*
G01X2136130Y583094D02*
X2135409Y582606D01*
G01X2136852Y583581D02*
X2136130Y583094D01*
G01X2137574Y584555D02*
X2136852Y583581D01*
G01X2131800Y578709D02*
X2132521Y577734D01*
G01X2131078Y579196D02*
X2131800Y578709D01*
G01X2130356Y579196D02*
X2131078D01*
G01X2129634Y578709D02*
X2130356Y579196D01*
G01X2128913Y577734D02*
X2129634Y578709D01*
G01X2128913Y576760D02*
Y577734D01*
G01X2129634Y575785D02*
X2128913Y576760D01*
G01X2130356Y575298D02*
X2129634Y575785D01*
G01X2131078Y575298D02*
X2130356D01*
G01X2131800Y575785D02*
X2131078Y575298D01*
G01X2132521Y576760D02*
X2131800Y575785D01*
G01X2136852D02*
X2135409Y574811D01*
G01X2137574Y576760D02*
X2136852Y575785D01*
G01X2145448Y672743D02*
G03I-5709J0D01*
G01X2117987Y720775D02*
Y759751D01*
G01X2134720Y715263D02*
G03X2135901I590J0D01*
G01Y708964D02*
G03X2134720I-590J0D01*
G01X2132751D02*
G03X2131570I-590J0D01*
G01Y715263D02*
G03X2132751I591J0D01*
G01X2134720D02*
G03X2135901I590J0D01*
G01Y708964D02*
G03X2134720I-590J0D01*
G01X2132751D02*
G03X2131570I-590J0D01*
G01Y715263D02*
G03X2132751I591J0D01*
G01X2121924Y720775D02*
G03X2117987Y716838I0J-3937D01*
G01X2114050Y692428D02*
G03X2117987Y696365I0J3937D01*
G01X2135089Y714138D02*
X2135097Y714113D01*
G01X2135048D02*
X2135039Y714138D01*
G01X2136688Y708964D02*
Y715263D01*
G01Y708964D02*
Y715263D01*
G01X2136491Y708964D02*
Y710539D01*
G01Y715263D02*
Y713688D01*
G01X2135769Y714205D02*
Y713811D01*
G01X2135720D02*
Y714138D01*
G01X2135671Y714079D02*
Y714146D01*
G01X2135605Y714205D02*
Y713811D01*
G01X2135556Y713870D02*
Y714205D01*
G01X2135326Y714155D02*
Y713811D01*
G01X2135277D02*
Y714205D01*
G01X2135212D02*
Y713811D01*
G01X2135162D02*
Y714205D01*
G01X2135097Y714113D02*
Y714079D01*
G01X2135048Y714088D02*
Y714113D01*
G01X2134843Y714163D02*
Y714038D01*
G01Y713987D02*
Y713811D01*
G01X2134793D02*
Y714205D01*
G01X2134129Y713688D02*
Y715263D01*
G01Y710539D02*
Y708964D01*
G01X2133342D02*
Y710539D01*
G01Y715263D02*
Y713688D01*
G01X2130979D02*
Y715263D01*
G01Y710539D02*
Y708964D01*
G01X2130783D02*
Y715263D01*
G01D02*
Y708964D01*
G01X2135532Y713811D02*
X2135326Y714155D01*
G01X2135351Y714205D02*
X2135556Y713870D01*
G01X2135097Y714079D02*
X2135089Y714054D01*
G01X2135039Y714063D02*
X2135048Y714088D01*
G01X2117987Y716838D02*
Y696365D01*
G01X2135064Y714172D02*
X2135089Y714138D01*
G01X2135039D02*
X2135023Y714155D01*
G01X2135089Y714054D02*
X2135064Y714021D01*
G01X2135031Y714197D02*
X2135064Y714172D01*
G01X2135023Y714046D02*
X2135039Y714063D01*
G01X2135720Y714138D02*
X2135671Y714079D01*
G01Y714146D02*
X2135720Y714205D01*
G01X2135064Y714021D02*
X2135031Y713996D01*
G01X2135023Y714155D02*
X2134998Y714163D01*
G01X2134990Y714205D02*
X2135031Y714197D01*
G01X2134998Y714038D02*
X2135023Y714046D01*
G01X2145546Y720775D02*
X2121924D01*
G01X2134129Y715263D02*
X2136491D01*
G01X2130979D02*
X2133342D01*
G01X2131570D02*
X2130783D01*
G01X2131570D02*
X2130783D01*
G01X2134720D02*
X2132751D01*
G01X2134720D02*
X2132751D01*
G01X2136688D02*
X2135901D01*
G01X2136688D02*
X2135901D01*
G01X2136688Y714279D02*
X2130783D01*
G01X2135720Y714205D02*
X2135769D01*
G01X2135556D02*
X2135605D01*
G01X2135277D02*
X2135351D01*
G01X2135162D02*
X2135212D01*
G01X2134793D02*
X2134990D01*
G01X2134998Y714163D02*
X2134843D01*
G01X2130783Y714082D02*
X2136688D01*
G01X2134843Y714038D02*
X2134998D01*
G01X2134990Y713987D02*
X2134843D01*
G01X2135769Y713811D02*
X2135720D01*
G01X2135605D02*
X2135532D01*
G01X2135326D02*
X2135277D01*
G01X2135212D02*
X2135162D01*
G01X2134843D02*
X2134793D01*
G01X2133342Y713688D02*
X2130979D01*
G01X2136491D02*
X2134129D01*
G01X2133342Y710539D02*
X2130979D01*
G01X2136491D02*
X2134129D01*
G01X2130783Y710145D02*
X2136688D01*
G01Y709948D02*
X2130783D01*
G01X2134129Y708964D02*
X2136491D01*
G01X2135901D02*
X2136688D01*
G01X2135901D02*
X2136688D01*
G01X2132751D02*
X2134720D01*
G01X2132751D02*
X2134720D01*
G01X2130979D02*
X2133342D01*
G01X2130783D02*
X2131570D01*
G01X2130783D02*
X2131570D01*
G01X2135031Y713996D02*
X2134990Y713987D01*
G01X2138657Y777724D02*
Y773826D01*
G01X2140100Y777237D02*
X2138657Y777724D01*
G01X2141544Y776749D02*
X2140100Y777237D01*
G01X2107161Y785519D02*
Y781621D01*
G01X2108604Y785032D02*
X2107161Y785519D01*
G01X2110048Y784545D02*
X2108604Y785032D01*
G01X2112213Y784057D02*
X2110048Y784545D01*
G01X2115822Y783570D02*
X2112213Y784057D01*
G01X2107882Y776749D02*
X2108604Y777237D01*
G01X2107161Y775775D02*
X2107882Y776749D01*
G01Y774800D02*
X2107161Y775775D01*
G01X2108604Y774313D02*
X2107882Y774800D01*
G01X2110048Y773826D02*
X2108604Y774313D01*
G01X2112935Y773826D02*
X2110048D01*
G01X2114378Y774313D02*
X2112935Y773826D01*
G01X2115100Y774800D02*
X2114378Y774313D01*
G01X2115822Y775775D02*
X2115100Y774800D01*
G01Y776749D02*
X2115822Y775775D01*
G01X2114378Y777237D02*
X2115100Y776749D01*
G01X2112935Y777724D02*
X2114378Y777237D01*
G01X2111491D02*
X2112935Y777724D01*
G01X2110770Y775775D02*
X2111491Y777237D01*
G01Y774313D02*
X2110770Y775775D01*
G01X2112935Y773826D02*
X2111491Y774313D01*
G01X2138657Y782596D02*
X2142266Y782109D01*
G01X2138657Y785519D02*
Y782596D01*
G01Y767980D02*
X2147318D01*
G01X2107161D02*
X2115822D01*
G01X2115100Y797699D02*
X2114378Y797212D01*
G01X2115822Y798673D02*
X2115100Y797699D01*
G01X2115822Y799648D02*
Y798673D01*
G01X2115100Y800622D02*
X2115822Y799648D01*
G01X2114378Y801109D02*
X2115100Y800622D01*
G01X2113657Y801597D02*
X2114378Y801109D01*
G01X2112935Y801597D02*
X2113657D01*
G01X2115100Y805494D02*
X2114378Y805007D01*
G01X2115822Y806469D02*
X2115100Y805494D01*
G01X2115822Y807443D02*
Y806469D01*
G01X2115100Y808418D02*
X2115822Y807443D01*
G01X2114378Y808905D02*
X2115100Y808418D01*
G01X2112935Y809392D02*
X2114378Y808905D01*
G01X2111491D02*
X2112935Y809392D01*
G01X2110770Y808418D02*
X2111491Y808905D01*
G01X2110048Y807443D02*
X2110770Y808418D01*
G01X2110048Y806469D02*
Y807443D01*
G01X2110770Y805494D02*
X2110048Y806469D01*
G01X2107161Y805982D02*
X2110770Y805494D01*
G01X2107161Y808905D02*
Y805982D01*
G01X2115100Y790878D02*
X2115822Y791365D01*
G01Y790878D02*
X2115100D01*
G01X2115822Y791365D02*
Y790878D01*
G01X2111491Y800622D02*
X2112935Y801597D01*
G01X2110770Y799648D02*
X2111491Y800622D01*
G01X2110048D02*
X2110770Y799648D01*
G01X2109326Y801109D02*
X2110048Y800622D01*
G01X2108604Y801109D02*
X2109326D01*
G01X2107882Y800622D02*
X2108604Y801109D01*
G01X2107161Y799648D02*
X2107882Y800622D01*
G01X2107161Y798673D02*
Y799648D01*
G01X2107882Y797699D02*
X2107161Y798673D01*
G01X2138657Y805982D02*
X2142266Y805494D01*
G01X2138657Y808905D02*
Y805982D01*
G01X2140822Y801109D02*
X2141544Y800622D01*
G01X2140100Y801109D02*
X2140822D01*
G01X2139378Y800622D02*
X2140100Y801109D01*
G01X2138657Y799648D02*
X2139378Y800622D01*
G01X2138657Y798673D02*
Y799648D01*
G01X2139378Y797699D02*
X2138657Y798673D01*
G01X2110770D02*
Y799648D01*
G01X2163676Y-618663D02*
Y-637600D01*
G01X2152002Y-428585D02*
Y-518714D01*
G01X2155670Y-473903D02*
X2569325D01*
G01X2180885Y266023D02*
X2287709D01*
G01X2177735D02*
X2180885D01*
G01X2178972Y290628D02*
G03X2182909Y294565I0J3937D01*
G01X2171689Y314250D02*
G03I-5020J0D01*
G01X2178480D02*
G03I-11811J0D01*
G01X2182909Y329998D02*
Y294565D01*
G01X2144917Y337872D02*
G03X2148854Y333935I3937J0D01*
G01X2182909Y329998D02*
G03X2178972Y333935I-3937J0D01*
G01X2144917Y337872D02*
Y358345D01*
G01X2178972Y333935D02*
X2148854D01*
G01X2184588Y540842D02*
X2183867Y540354D01*
G01X2185310Y541816D02*
X2184588Y540842D01*
G01X2185310Y542790D02*
Y541816D01*
G01X2184588Y543765D02*
X2185310Y542790D01*
G01X2183867Y544252D02*
X2184588Y543765D01*
G01X2182423Y544739D02*
X2183867Y544252D01*
G01X2180979D02*
X2182423Y544739D01*
G01X2180258Y543765D02*
X2180979Y544252D01*
G01X2179536Y542790D02*
X2180258Y543765D01*
G01X2179536Y541816D02*
Y542790D01*
G01X2180258Y540842D02*
X2179536Y541816D01*
G01X2176649Y541329D02*
X2180258Y540842D01*
G01X2176649Y544252D02*
Y541329D01*
G01X2179536Y535970D02*
X2180258Y534995D01*
G01X2178814Y536457D02*
X2179536Y535970D01*
G01X2178092Y536457D02*
X2178814D01*
G01X2177371Y535970D02*
X2178092Y536457D01*
G01X2176649Y534995D02*
X2177371Y535970D01*
G01X2176649Y534021D02*
Y534995D01*
G01X2177371Y533046D02*
X2176649Y534021D01*
G01X2178092Y532559D02*
X2177371Y533046D01*
G01X2178814Y532559D02*
X2178092D01*
G01X2179536Y533046D02*
X2178814Y532559D01*
G01X2180258Y534021D02*
X2179536Y533046D01*
G01X2185310Y534995D02*
Y534021D01*
G01X2184588Y535970D02*
X2185310Y534995D01*
G01X2183867Y536457D02*
X2184588Y535970D01*
G01X2183145Y536944D02*
X2183867Y536457D01*
G01X2182423Y536944D02*
X2183145D01*
G01X2181701Y536457D02*
X2182423Y536944D01*
G01X2180979Y535970D02*
X2181701Y536457D01*
G01X2180258Y534995D02*
X2180979Y535970D01*
G01X2180258Y534021D02*
Y534995D01*
G01X2180979Y533046D02*
X2180258Y534021D01*
G01X2181701Y532559D02*
X2180979Y533046D01*
G01X2182423Y532072D02*
X2181701Y532559D01*
G01X2183145Y532072D02*
X2182423D01*
G01X2184588Y533046D02*
X2183145Y532072D01*
G01X2185310Y534021D02*
X2184588Y533046D01*
G01X2176649Y526713D02*
X2185310D01*
G01X2187476Y653058D02*
Y573917D01*
G01X2169070Y580279D02*
Y579305D01*
G01X2168348Y581254D02*
X2169070Y580279D01*
G01X2167626Y581741D02*
X2168348Y581254D01*
G01X2166905Y582228D02*
X2167626Y581741D01*
G01X2166183Y582228D02*
X2166905D01*
G01X2165461Y581741D02*
X2166183Y582228D01*
G01X2164739Y581254D02*
X2165461Y581741D01*
G01X2164018Y580279D02*
X2164739Y581254D01*
G01X2164018Y579305D02*
Y580279D01*
G01X2164739Y578331D02*
X2164018Y579305D01*
G01X2165461Y577843D02*
X2164739Y578331D01*
G01X2166183Y577356D02*
X2165461Y577843D01*
G01X2166905Y577356D02*
X2166183D01*
G01X2168348Y594896D02*
X2169070Y595383D01*
G01Y594896D02*
X2168348D01*
G01X2169070Y595383D02*
Y594896D01*
G01X2184588Y549611D02*
X2185310Y550098D01*
G01Y549611D02*
X2184588D01*
G01X2185310Y550098D02*
Y549611D01*
G01X2168348Y588562D02*
X2169070Y587587D01*
G01X2167626Y589049D02*
X2168348Y588562D01*
G01X2166183Y589536D02*
X2167626Y589049D01*
G01X2163296Y589536D02*
X2166183D01*
G01X2161852Y589049D02*
X2163296Y589536D01*
G01X2161130Y588562D02*
X2161852Y589049D01*
G01X2160409Y587587D02*
X2161130Y588562D01*
G01Y586613D02*
X2160409Y587587D01*
G01X2161852Y586126D02*
X2161130Y586613D01*
G01X2163296Y585639D02*
X2161852Y586126D01*
G01X2166183Y585639D02*
X2163296D01*
G01X2167626Y586126D02*
X2166183Y585639D01*
G01X2168348Y586613D02*
X2167626Y586126D01*
G01X2169070Y587587D02*
X2168348Y586613D01*
G01X2163296Y581254D02*
X2164018Y580279D01*
G01X2162574Y581741D02*
X2163296Y581254D01*
G01X2161852Y581741D02*
X2162574D01*
G01X2161130Y581254D02*
X2161852Y581741D01*
G01X2160409Y580279D02*
X2161130Y581254D01*
G01X2160409Y579305D02*
Y580279D01*
G01X2161130Y578331D02*
X2160409Y579305D01*
G01X2161852Y577843D02*
X2161130Y578331D01*
G01X2162574Y577843D02*
X2161852D01*
G01X2163296Y578331D02*
X2162574Y577843D01*
G01X2164018Y579305D02*
X2163296Y578331D01*
G01X2168348D02*
X2166905Y577356D01*
G01X2169070Y579305D02*
X2168348Y578331D01*
G01X2184588Y566663D02*
X2185310Y565689D01*
G01X2183867Y567151D02*
X2184588Y566663D01*
G01X2182423Y567638D02*
X2183867Y567151D01*
G01X2179536Y567638D02*
X2182423D01*
G01X2178092Y567151D02*
X2179536Y567638D01*
G01X2177371Y566663D02*
X2178092Y567151D01*
G01X2176649Y565689D02*
X2177371Y566663D01*
G01Y564715D02*
X2176649Y565689D01*
G01X2178092Y564227D02*
X2177371Y564715D01*
G01X2179536Y563740D02*
X2178092Y564227D01*
G01X2182423Y563740D02*
X2179536D01*
G01X2183867Y564227D02*
X2182423Y563740D01*
G01X2184588Y564715D02*
X2183867Y564227D01*
G01X2185310Y565689D02*
X2184588Y564715D01*
G01Y558868D02*
X2185310Y557894D01*
G01X2183867Y559355D02*
X2184588Y558868D01*
G01X2182423Y559843D02*
X2183867Y559355D01*
G01X2179536Y559843D02*
X2182423D01*
G01X2178092Y559355D02*
X2179536Y559843D01*
G01X2177371Y558868D02*
X2178092Y559355D01*
G01X2176649Y557894D02*
X2177371Y558868D01*
G01Y556919D02*
X2176649Y557894D01*
G01X2178092Y556432D02*
X2177371Y556919D01*
G01X2179536Y555945D02*
X2178092Y556432D01*
G01X2182423Y555945D02*
X2179536D01*
G01X2183867Y556432D02*
X2182423Y555945D01*
G01X2184588Y556919D02*
X2183867Y556432D01*
G01X2185310Y557894D02*
X2184588Y556919D01*
G01X2160409Y571997D02*
X2169070D01*
G01X2171235Y668806D02*
Y619202D01*
G01X2169070Y603665D02*
Y602691D01*
G01X2168348Y604640D02*
X2169070Y603665D01*
G01X2167626Y605127D02*
X2168348Y604640D01*
G01X2166905Y605614D02*
X2167626Y605127D01*
G01X2166183Y605614D02*
X2166905D01*
G01X2165461Y605127D02*
X2166183Y605614D01*
G01X2164739Y604640D02*
X2165461Y605127D01*
G01X2164018Y603665D02*
X2164739Y604640D01*
G01X2164018Y602691D02*
Y603665D01*
G01X2164739Y601716D02*
X2164018Y602691D01*
G01X2165461Y601229D02*
X2164739Y601716D01*
G01X2166183Y600742D02*
X2165461Y601229D01*
G01X2166905Y600742D02*
X2166183D01*
G01X2169070Y611461D02*
Y610486D01*
G01X2168348Y612435D02*
X2169070Y611461D01*
G01X2167626Y612922D02*
X2168348Y612435D01*
G01X2166905Y613409D02*
X2167626Y612922D01*
G01X2166183Y613409D02*
X2166905D01*
G01X2164739Y612435D02*
X2166183Y613409D01*
G01X2163296Y612435D02*
X2164018Y611461D01*
G01X2162574Y612922D02*
X2163296Y612435D01*
G01X2161852Y612922D02*
X2162574D01*
G01X2161130Y612435D02*
X2161852Y612922D01*
G01X2160409Y611461D02*
X2161130Y612435D01*
G01X2160409Y610486D02*
Y611461D01*
G01X2161130Y609512D02*
X2160409Y610486D01*
G01X2161852Y609024D02*
X2161130Y609512D01*
G01X2162574Y609024D02*
X2161852D01*
G01X2163296Y609512D02*
X2162574Y609024D01*
G01X2164018Y610486D02*
X2163296Y609512D01*
G01X2164018Y611461D02*
X2164739Y612435D01*
G01X2164018Y610486D02*
Y611461D01*
G01X2164739Y609512D02*
X2164018Y610486D01*
G01X2165461Y609024D02*
X2164739Y609512D01*
G01X2166183Y608537D02*
X2165461Y609024D01*
G01X2166905Y608537D02*
X2166183D01*
G01X2167626Y609024D02*
X2166905Y608537D01*
G01X2168348Y609512D02*
X2167626Y609024D01*
G01X2169070Y610486D02*
X2168348Y609512D01*
G01X2163296Y604640D02*
X2164018Y603665D01*
G01X2162574Y605127D02*
X2163296Y604640D01*
G01X2161852Y605127D02*
X2162574D01*
G01X2161130Y604640D02*
X2161852Y605127D01*
G01X2160409Y603665D02*
X2161130Y604640D01*
G01X2160409Y602691D02*
Y603665D01*
G01X2161130Y601716D02*
X2160409Y602691D01*
G01X2161852Y601229D02*
X2161130Y601716D01*
G01X2162574Y601229D02*
X2161852D01*
G01X2163296Y601716D02*
X2162574Y601229D01*
G01X2164018Y602691D02*
X2163296Y601716D01*
G01X2168348D02*
X2166905Y600742D01*
G01X2169070Y602691D02*
X2168348Y601716D01*
G01X2187476Y688491D02*
G03X2183539Y692428I-3937J0D01*
G01Y649121D02*
G03X2187476Y653058I0J3937D01*
G01X2176255Y672743D02*
G03I-5020J0D01*
G01X2183046D02*
G03I-11811J0D01*
G01X2187476Y688491D02*
Y653058D01*
G01X2149483Y720775D02*
Y759751D01*
G01Y716838D02*
G03X2145546Y720775I-3937J0D01*
G01X2149483Y696365D02*
G03X2153420Y692428I3937J0D01*
G01X2149483Y696365D02*
Y716838D01*
G01X2183539Y692428D02*
X2153420D01*
G01X2143709Y776262D02*
X2141544Y776749D01*
G01X2147318Y775775D02*
X2143709Y776262D01*
G01X2146596Y782109D02*
X2145875Y781621D01*
G01X2147318Y783083D02*
X2146596Y782109D01*
G01X2147318Y784057D02*
Y783083D01*
G01X2146596Y785032D02*
X2147318Y784057D01*
G01X2145875Y785519D02*
X2146596Y785032D01*
G01X2144431Y786006D02*
X2145875Y785519D01*
G01X2142987D02*
X2144431Y786006D01*
G01X2142266Y785032D02*
X2142987Y785519D01*
G01X2141544Y784057D02*
X2142266Y785032D01*
G01X2141544Y783083D02*
Y784057D01*
G01X2142266Y782109D02*
X2141544Y783083D01*
G01X2146596Y797699D02*
X2145875Y797212D01*
G01X2147318Y798673D02*
X2146596Y797699D01*
G01X2147318Y799648D02*
Y798673D01*
G01X2146596Y800622D02*
X2147318Y799648D01*
G01X2145875Y801109D02*
X2146596Y800622D01*
G01X2145153Y801597D02*
X2145875Y801109D01*
G01X2144431Y801597D02*
X2145153D01*
G01X2146596Y805494D02*
X2145875Y805007D01*
G01X2147318Y806469D02*
X2146596Y805494D01*
G01X2147318Y807443D02*
Y806469D01*
G01X2146596Y808418D02*
X2147318Y807443D01*
G01X2145875Y808905D02*
X2146596Y808418D01*
G01X2144431Y809392D02*
X2145875Y808905D01*
G01X2142987D02*
X2144431Y809392D01*
G01X2142266Y808418D02*
X2142987Y808905D01*
G01X2141544Y807443D02*
X2142266Y808418D01*
G01X2141544Y806469D02*
Y807443D01*
G01X2142266Y805494D02*
X2141544Y806469D01*
G01X2142987Y800622D02*
X2144431Y801597D01*
G01X2142266Y799648D02*
X2142987Y800622D01*
G01X2141544D02*
X2142266Y799648D01*
G01X2146596Y790878D02*
X2147318Y791365D01*
G01Y790878D02*
X2146596D01*
G01X2147318Y791365D02*
Y790878D01*
G01X2142266Y798673D02*
Y799648D01*
G01X2163676Y1559093D02*
Y1540156D01*
G01X2212301Y268910D02*
X2212788Y268188D01*
G01X2212301D02*
Y268910D01*
G01X2212788Y268188D02*
X2212301D01*
G01X2229353Y268910D02*
X2228378Y268188D01*
G01X2229840Y269632D02*
X2229353Y268910D01*
G01X2230327Y271075D02*
X2229840Y269632D01*
G01X2230327Y273962D02*
Y271075D01*
G01X2229840Y275406D02*
X2230327Y273962D01*
G01X2229353Y276128D02*
X2229840Y275406D01*
G01X2228378Y276849D02*
X2229353Y276128D01*
G01X2227404D02*
X2228378Y276849D01*
G01X2226917Y275406D02*
X2227404Y276128D01*
G01X2226430Y273962D02*
X2226917Y275406D01*
G01X2226430Y271075D02*
Y273962D01*
G01X2226917Y269632D02*
X2226430Y271075D01*
G01X2227404Y268910D02*
X2226917Y269632D01*
G01X2228378Y268188D02*
X2227404Y268910D01*
G01X2203044Y268188D02*
X2206941D01*
G01X2203531Y270353D02*
X2203044Y268188D01*
G01X2204505Y271797D02*
X2203531Y270353D01*
G01X2206454Y273240D02*
X2204505Y271797D01*
G01X2190268Y270353D02*
X2189546Y272519D01*
G01X2191712Y268910D02*
X2190268Y270353D01*
G01X2193877Y268188D02*
X2191712Y268910D01*
G01X2196043D02*
X2193877Y268188D01*
G01X2197486Y270353D02*
X2196043Y268910D01*
G01X2198208Y272519D02*
X2197486Y270353D01*
G01Y274684D02*
X2198208Y272519D01*
G01X2196043Y276128D02*
X2197486Y274684D01*
G01X2193877Y276849D02*
X2196043Y276128D01*
G01X2191712D02*
X2193877Y276849D01*
G01X2190268Y274684D02*
X2191712Y276128D01*
G01X2189546Y272519D02*
X2190268Y274684D01*
G01X2219609Y268910D02*
X2219122Y269632D01*
G01X2220583Y268188D02*
X2219609Y268910D01*
G01X2221558D02*
X2220583Y268188D01*
G01X2222045Y269632D02*
X2221558Y268910D01*
G01X2222532Y271075D02*
X2222045Y269632D01*
G01X2222532Y273962D02*
Y271075D01*
G01X2222045Y275406D02*
X2222532Y273962D01*
G01X2221558Y276128D02*
X2222045Y275406D01*
G01X2220583Y276849D02*
X2221558Y276128D01*
G01X2219609D02*
X2220583Y276849D01*
G01X2219122Y275406D02*
X2219609Y276128D01*
G01X2218634Y273962D02*
X2219122Y275406D01*
G01Y272519D02*
X2218634Y273962D01*
G01X2220583Y271797D02*
X2219122Y272519D01*
G01X2222045D02*
X2220583Y271797D01*
G01X2222532Y273962D02*
X2222045Y272519D01*
G01X2206941Y273962D02*
X2206454Y273240D01*
G01X2206941Y275406D02*
Y273962D01*
G01X2206454Y276128D02*
X2206941Y275406D01*
G01X2205480Y276849D02*
X2206454Y276128D01*
G01X2204505Y276849D02*
X2205480D01*
G01X2203531Y276128D02*
X2204505Y276849D01*
G01X2203044Y275406D02*
X2203531Y276128D01*
G01X2235687Y269632D02*
X2236661Y268188D01*
G01X2235199Y271797D02*
X2235687Y269632D01*
G01X2235199Y273240D02*
Y271797D01*
G01X2235687Y275406D02*
X2235199Y273240D01*
G01X2236661Y276849D02*
X2235687Y275406D01*
G01X2190268Y266023D02*
X2197486Y279015D01*
G01X2245918Y268188D02*
Y276849D01*
G01X2242020D02*
X2245918Y268188D01*
G01X2242020D02*
Y276849D01*
G01X2252251Y272519D02*
X2249816D01*
G01X2253226Y273240D02*
X2252251Y272519D01*
G01X2253713Y273962D02*
X2253226Y273240D01*
G01X2253713Y275406D02*
Y273962D01*
G01X2253226Y276128D02*
X2253713Y275406D01*
G01X2252251Y276849D02*
X2253226Y276128D01*
G01X2249816Y276849D02*
X2252251D01*
G01X2249816Y268188D02*
Y276849D01*
G01X2275637Y269632D02*
X2274663Y268188D01*
G01X2276125Y271797D02*
X2275637Y269632D01*
G01X2276125Y273240D02*
Y271797D01*
G01X2275637Y275406D02*
X2276125Y273240D01*
G01X2274663Y276849D02*
X2275637Y275406D01*
G01X2269304Y276849D02*
Y268188D01*
G01X2265406Y276849D02*
Y268188D01*
G01X2259560Y276849D02*
Y268188D01*
G01X2257124Y276849D02*
X2261996D01*
G01X2265406Y272519D02*
X2269304D01*
G01X2277987Y1540156D02*
X2608695D01*
G01X2340978Y-428585D02*
Y-518714D01*
G01X2383345Y-618663D02*
Y-637600D01*
G01Y1559093D02*
Y1540156D01*
G01X2569325Y-579293D02*
Y-323507D01*
G01X2608695Y1540156D02*
Y-618663D01*
G01X2608696Y-473978D02*
Y-618663D01*
G01X2608695Y-402781D02*
X2627632D01*
G01X2608695Y-186899D02*
X2627632D01*
G01X2608695Y28983D02*
X2627632D01*
G01X2608695Y244865D02*
X2627632D01*
G01X2608695Y460747D02*
X2627632D01*
G01X2608695Y676628D02*
X2627632D01*
G01X2608695Y892510D02*
X2627632D01*
G01X2608695Y1108392D02*
X2627632D01*
G01X2608506Y1324274D02*
X2627443D01*
G01X2608695Y1540156D02*
Y1445668D01*
G01X2627632Y1559093D02*
Y-637600D01*
M02*
